(kicad_sch (version 20230121) (generator eeschema)

  (paper "A3")

  (title_block
    (title "Kria K26 Devboard")
    (date "2024-03-26")
    (rev "1.2.5")
    (company "Antmicro")
    (comment 1 "www.antmicro.com")
    (comment 2 "Antmicro Ltd.")
  )

  (junction (at 50.165 160.02) (diameter 0) (color 0 0 0 0)
  )
  (junction (at 155.575 213.36) (diameter 0) (color 0 0 0 0)
  )
  (junction (at 375.92 50.8) (diameter 0) (color 0 0 0 0)
  )
  (junction (at 375.92 104.14) (diameter 0) (color 0 0 0 0)
  )
  (junction (at 278.13 152.4) (diameter 0) (color 0 0 0 0)
  )
  (junction (at 245.11 78.74) (diameter 0) (color 0 0 0 0)
  )
  (junction (at 245.11 38.1) (diameter 0) (color 0 0 0 0)
  )
  (junction (at 146.05 147.32) (diameter 0) (color 0 0 0 0)
  )
  (junction (at 375.92 111.76) (diameter 0) (color 0 0 0 0)
  )
  (junction (at 146.05 43.18) (diameter 0) (color 0 0 0 0)
  )
  (junction (at 146.05 58.42) (diameter 0) (color 0 0 0 0)
  )
  (junction (at 278.13 142.24) (diameter 0) (color 0 0 0 0)
  )
  (junction (at 50.165 137.16) (diameter 0) (color 0 0 0 0)
  )
  (junction (at 146.05 170.18) (diameter 0) (color 0 0 0 0)
  )
  (junction (at 81.915 154.94) (diameter 0) (color 0 0 0 0)
  )
  (junction (at 88.265 215.9) (diameter 0) (color 0 0 0 0)
  )
  (junction (at 81.915 53.34) (diameter 0) (color 0 0 0 0)
  )
  (junction (at 340.36 101.6) (diameter 0) (color 0 0 0 0)
  )
  (junction (at 85.09 55.88) (diameter 0) (color 0 0 0 0)
  )
  (junction (at 146.05 27.94) (diameter 0) (color 0 0 0 0)
  )
  (junction (at 81.915 144.78) (diameter 0) (color 0 0 0 0)
  )
  (junction (at 134.62 213.36) (diameter 0) (color 0 0 0 0)
  )
  (junction (at 340.36 71.12) (diameter 0) (color 0 0 0 0)
  )
  (junction (at 340.36 55.88) (diameter 0) (color 0 0 0 0)
  )
  (junction (at 50.165 149.86) (diameter 0) (color 0 0 0 0)
  )
  (junction (at 146.05 86.36) (diameter 0) (color 0 0 0 0)
  )
  (junction (at 245.11 27.94) (diameter 0) (color 0 0 0 0)
  )
  (junction (at 50.165 35.56) (diameter 0) (color 0 0 0 0)
  )
  (junction (at 340.36 124.46) (diameter 0) (color 0 0 0 0)
  )
  (junction (at 375.92 132.08) (diameter 0) (color 0 0 0 0)
  )
  (junction (at 148.59 196.85) (diameter 0) (color 0 0 0 0)
  )
  (junction (at 340.36 157.48) (diameter 0) (color 0 0 0 0)
  )
  (junction (at 146.05 35.56) (diameter 0) (color 0 0 0 0)
  )
  (junction (at 180.34 25.4) (diameter 0) (color 0 0 0 0)
  )
  (junction (at 375.92 81.28) (diameter 0) (color 0 0 0 0)
  )
  (junction (at 81.915 101.6) (diameter 0) (color 0 0 0 0)
  )
  (junction (at 375.92 88.9) (diameter 0) (color 0 0 0 0)
  )
  (junction (at 245.11 116.84) (diameter 0) (color 0 0 0 0)
  )
  (junction (at 278.13 73.66) (diameter 0) (color 0 0 0 0)
  )
  (junction (at 50.165 106.68) (diameter 0) (color 0 0 0 0)
  )
  (junction (at 278.13 40.64) (diameter 0) (color 0 0 0 0)
  )
  (junction (at 50.165 139.7) (diameter 0) (color 0 0 0 0)
  )
  (junction (at 245.11 137.16) (diameter 0) (color 0 0 0 0)
  )
  (junction (at 278.13 88.9) (diameter 0) (color 0 0 0 0)
  )
  (junction (at 96.52 215.9) (diameter 0) (color 0 0 0 0)
  )
  (junction (at 50.165 68.58) (diameter 0) (color 0 0 0 0)
  )
  (junction (at 99.695 196.85) (diameter 0) (color 0 0 0 0)
  )
  (junction (at 146.05 96.52) (diameter 0) (color 0 0 0 0)
  )
  (junction (at 278.13 66.04) (diameter 0) (color 0 0 0 0)
  )
  (junction (at 375.92 96.52) (diameter 0) (color 0 0 0 0)
  )
  (junction (at 45.72 175.26) (diameter 0) (color 0 0 0 0)
  )
  (junction (at 375.92 73.66) (diameter 0) (color 0 0 0 0)
  )
  (junction (at 127.635 196.85) (diameter 0) (color 0 0 0 0)
  )
  (junction (at 340.36 93.98) (diameter 0) (color 0 0 0 0)
  )
  (junction (at 146.05 149.86) (diameter 0) (color 0 0 0 0)
  )
  (junction (at 146.05 139.7) (diameter 0) (color 0 0 0 0)
  )
  (junction (at 50.165 43.18) (diameter 0) (color 0 0 0 0)
  )
  (junction (at 304.8 196.85) (diameter 0) (color 0 0 0 0)
  )
  (junction (at 247.65 222.25) (diameter 0) (color 0 0 0 0)
  )
  (junction (at 278.13 96.52) (diameter 0) (color 0 0 0 0)
  )
  (junction (at 375.92 40.64) (diameter 0) (color 0 0 0 0)
  )
  (junction (at 245.11 147.32) (diameter 0) (color 0 0 0 0)
  )
  (junction (at 50.165 212.725) (diameter 0) (color 0 0 0 0)
  )
  (junction (at 146.05 66.04) (diameter 0) (color 0 0 0 0)
  )
  (junction (at 245.11 55.88) (diameter 0) (color 0 0 0 0)
  )
  (junction (at 245.11 157.48) (diameter 0) (color 0 0 0 0)
  )
  (junction (at 247.65 196.85) (diameter 0) (color 0 0 0 0)
  )
  (junction (at 375.92 127) (diameter 0) (color 0 0 0 0)
  )
  (junction (at 245.745 267.97) (diameter 0) (color 0 0 0 0)
  )
  (junction (at 81.915 111.76) (diameter 0) (color 0 0 0 0)
  )
  (junction (at 267.97 196.85) (diameter 0) (color 0 0 0 0)
  )
  (junction (at 245.11 45.72) (diameter 0) (color 0 0 0 0)
  )
  (junction (at 144.145 175.26) (diameter 0) (color 0 0 0 0)
  )
  (junction (at 141.605 213.36) (diameter 0) (color 0 0 0 0)
  )
  (junction (at 375.92 66.04) (diameter 0) (color 0 0 0 0)
  )
  (junction (at 81.915 142.24) (diameter 0) (color 0 0 0 0)
  )
  (junction (at 278.13 43.18) (diameter 0) (color 0 0 0 0)
  )
  (junction (at 245.11 109.22) (diameter 0) (color 0 0 0 0)
  )
  (junction (at 81.915 81.28) (diameter 0) (color 0 0 0 0)
  )
  (junction (at 375.92 58.42) (diameter 0) (color 0 0 0 0)
  )
  (junction (at 340.36 109.22) (diameter 0) (color 0 0 0 0)
  )
  (junction (at 146.05 160.02) (diameter 0) (color 0 0 0 0)
  )
  (junction (at 146.05 50.8) (diameter 0) (color 0 0 0 0)
  )
  (junction (at 278.13 132.08) (diameter 0) (color 0 0 0 0)
  )
  (junction (at 340.36 137.16) (diameter 0) (color 0 0 0 0)
  )
  (junction (at 50.165 76.2) (diameter 0) (color 0 0 0 0)
  )
  (junction (at 81.915 91.44) (diameter 0) (color 0 0 0 0)
  )
  (junction (at 81.915 172.72) (diameter 0) (color 0 0 0 0)
  )
  (junction (at 50.165 127) (diameter 0) (color 0 0 0 0)
  )
  (junction (at 146.05 106.68) (diameter 0) (color 0 0 0 0)
  )
  (junction (at 88.265 230.505) (diameter 0) (color 0 0 0 0)
  )
  (junction (at 245.11 167.64) (diameter 0) (color 0 0 0 0)
  )
  (junction (at 278.13 104.14) (diameter 0) (color 0 0 0 0)
  )
  (junction (at 41.275 212.725) (diameter 0) (color 0 0 0 0)
  )
  (junction (at 81.915 45.72) (diameter 0) (color 0 0 0 0)
  )
  (junction (at 245.11 63.5) (diameter 0) (color 0 0 0 0)
  )
  (junction (at 245.11 48.26) (diameter 0) (color 0 0 0 0)
  )
  (junction (at 245.11 35.56) (diameter 0) (color 0 0 0 0)
  )
  (junction (at 340.36 86.36) (diameter 0) (color 0 0 0 0)
  )
  (junction (at 81.915 60.96) (diameter 0) (color 0 0 0 0)
  )
  (junction (at 245.11 124.46) (diameter 0) (color 0 0 0 0)
  )
  (junction (at 340.36 78.74) (diameter 0) (color 0 0 0 0)
  )
  (junction (at 81.915 152.4) (diameter 0) (color 0 0 0 0)
  )
  (junction (at 146.05 116.84) (diameter 0) (color 0 0 0 0)
  )
  (junction (at 81.915 121.92) (diameter 0) (color 0 0 0 0)
  )
  (junction (at 50.165 170.18) (diameter 0) (color 0 0 0 0)
  )
  (junction (at 146.05 127) (diameter 0) (color 0 0 0 0)
  )
  (junction (at 257.81 222.25) (diameter 0) (color 0 0 0 0)
  )
  (junction (at 50.165 167.64) (diameter 0) (color 0 0 0 0)
  )
  (junction (at 141.605 196.85) (diameter 0) (color 0 0 0 0)
  )
  (junction (at 257.81 196.85) (diameter 0) (color 0 0 0 0)
  )
  (junction (at 340.36 27.94) (diameter 0) (color 0 0 0 0)
  )
  (junction (at 50.165 147.32) (diameter 0) (color 0 0 0 0)
  )
  (junction (at 278.13 127) (diameter 0) (color 0 0 0 0)
  )
  (junction (at 81.915 38.1) (diameter 0) (color 0 0 0 0)
  )
  (junction (at 340.36 132.08) (diameter 0) (color 0 0 0 0)
  )
  (junction (at 340.36 38.1) (diameter 0) (color 0 0 0 0)
  )
  (junction (at 278.13 50.8) (diameter 0) (color 0 0 0 0)
  )
  (junction (at 88.265 196.85) (diameter 0) (color 0 0 0 0)
  )
  (junction (at 340.36 48.26) (diameter 0) (color 0 0 0 0)
  )
  (junction (at 146.05 167.64) (diameter 0) (color 0 0 0 0)
  )
  (junction (at 375.92 162.56) (diameter 0) (color 0 0 0 0)
  )
  (junction (at 127.635 213.36) (diameter 0) (color 0 0 0 0)
  )
  (junction (at 245.11 71.12) (diameter 0) (color 0 0 0 0)
  )
  (junction (at 116.205 196.85) (diameter 0) (color 0 0 0 0)
  )
  (junction (at 278.13 81.28) (diameter 0) (color 0 0 0 0)
  )
  (junction (at 278.13 111.76) (diameter 0) (color 0 0 0 0)
  )
  (junction (at 50.165 88.9) (diameter 0) (color 0 0 0 0)
  )
  (junction (at 375.92 152.4) (diameter 0) (color 0 0 0 0)
  )
  (junction (at 314.96 196.85) (diameter 0) (color 0 0 0 0)
  )
  (junction (at 81.915 165.1) (diameter 0) (color 0 0 0 0)
  )
  (junction (at 375.92 142.24) (diameter 0) (color 0 0 0 0)
  )
  (junction (at 340.36 35.56) (diameter 0) (color 0 0 0 0)
  )
  (junction (at 314.96 222.25) (diameter 0) (color 0 0 0 0)
  )
  (junction (at 245.11 93.98) (diameter 0) (color 0 0 0 0)
  )
  (junction (at 304.8 222.25) (diameter 0) (color 0 0 0 0)
  )
  (junction (at 104.775 206.375) (diameter 0) (color 0 0 0 0)
  )
  (junction (at 59.055 212.725) (diameter 0) (color 0 0 0 0)
  )
  (junction (at 258.445 265.43) (diameter 0) (color 0 0 0 0)
  )
  (junction (at 340.36 45.72) (diameter 0) (color 0 0 0 0)
  )
  (junction (at 245.11 101.6) (diameter 0) (color 0 0 0 0)
  )
  (junction (at 278.13 162.56) (diameter 0) (color 0 0 0 0)
  )
  (junction (at 155.575 196.85) (diameter 0) (color 0 0 0 0)
  )
  (junction (at 146.05 157.48) (diameter 0) (color 0 0 0 0)
  )
  (junction (at 267.97 222.25) (diameter 0) (color 0 0 0 0)
  )
  (junction (at 148.59 213.36) (diameter 0) (color 0 0 0 0)
  )
  (junction (at 340.36 167.64) (diameter 0) (color 0 0 0 0)
  )
  (junction (at 50.165 157.48) (diameter 0) (color 0 0 0 0)
  )
  (junction (at 81.915 71.12) (diameter 0) (color 0 0 0 0)
  )
  (junction (at 278.13 119.38) (diameter 0) (color 0 0 0 0)
  )
  (junction (at 81.915 162.56) (diameter 0) (color 0 0 0 0)
  )
  (junction (at 245.11 132.08) (diameter 0) (color 0 0 0 0)
  )
  (junction (at 278.13 33.02) (diameter 0) (color 0 0 0 0)
  )
  (junction (at 340.36 63.5) (diameter 0) (color 0 0 0 0)
  )
  (junction (at 340.36 147.32) (diameter 0) (color 0 0 0 0)
  )
  (junction (at 146.05 76.2) (diameter 0) (color 0 0 0 0)
  )
  (junction (at 340.36 116.84) (diameter 0) (color 0 0 0 0)
  )
  (junction (at 81.915 132.08) (diameter 0) (color 0 0 0 0)
  )
  (junction (at 134.62 196.85) (diameter 0) (color 0 0 0 0)
  )
  (junction (at 50.165 58.42) (diameter 0) (color 0 0 0 0)
  )
  (junction (at 262.255 265.43) (diameter 0) (color 0 0 0 0)
  )
  (junction (at 278.13 58.42) (diameter 0) (color 0 0 0 0)
  )
  (junction (at 375.92 43.18) (diameter 0) (color 0 0 0 0)
  )
  (junction (at 245.11 86.36) (diameter 0) (color 0 0 0 0)
  )
  (junction (at 50.165 116.84) (diameter 0) (color 0 0 0 0)
  )
  (junction (at 375.92 33.02) (diameter 0) (color 0 0 0 0)
  )
  (junction (at 50.165 50.8) (diameter 0) (color 0 0 0 0)
  )
  (junction (at 375.92 119.38) (diameter 0) (color 0 0 0 0)
  )

  (no_connect (at 80.01 119.38))
  (no_connect (at 176.53 139.7))
  (no_connect (at 52.07 101.6))
  (no_connect (at 52.07 104.14))
  (no_connect (at 148.59 137.16))

  (bus_entry (at 196.85 96.52) (size -2.54 2.54)
    (stroke (width 0) (type default))
  )
  (bus_entry (at 129.54 111.76) (size -2.54 -2.54)
    (stroke (width 0) (type default))
  )
  (bus_entry (at 194.31 114.3) (size 2.54 -2.54)
    (stroke (width 0) (type default))
  )
  (bus_entry (at 100.33 114.3) (size -2.54 2.54)
    (stroke (width 0) (type default))
  )
  (bus_entry (at 97.79 127) (size 2.54 -2.54)
    (stroke (width 0) (type default))
  )
  (bus_entry (at 194.31 129.54) (size 2.54 -2.54)
    (stroke (width 0) (type default))
  )
  (bus_entry (at 127 111.76) (size 2.54 2.54)
    (stroke (width 0) (type default))
  )
  (bus_entry (at 100.33 111.76) (size -2.54 2.54)
    (stroke (width 0) (type default))
  )
  (bus_entry (at 97.79 129.54) (size 2.54 -2.54)
    (stroke (width 0) (type default))
  )
  (bus_entry (at 196.85 106.68) (size -2.54 2.54)
    (stroke (width 0) (type default))
  )
  (bus_entry (at 194.31 119.38) (size 2.54 -2.54)
    (stroke (width 0) (type default))
  )
  (bus_entry (at 194.31 96.52) (size 2.54 -2.54)
    (stroke (width 0) (type default))
  )
  (bus_entry (at 194.31 127) (size 2.54 -2.54)
    (stroke (width 0) (type default))
  )
  (bus_entry (at 129.54 129.54) (size -2.54 -2.54)
    (stroke (width 0) (type default))
  )
  (bus_entry (at 127 106.68) (size 2.54 2.54)
    (stroke (width 0) (type default))
  )
  (bus_entry (at 97.79 124.46) (size 2.54 -2.54)
    (stroke (width 0) (type default))
  )
  (bus_entry (at 194.31 134.62) (size 2.54 -2.54)
    (stroke (width 0) (type default))
  )
  (bus_entry (at 107.95 71.12) (size -2.54 2.54)
    (stroke (width 0) (type default))
  )
  (bus_entry (at 97.79 139.7) (size 2.54 -2.54)
    (stroke (width 0) (type default))
  )
  (bus_entry (at 194.31 137.16) (size 2.54 -2.54)
    (stroke (width 0) (type default))
  )
  (bus_entry (at 34.29 121.92) (size -2.54 -2.54)
    (stroke (width 0) (type default))
  )
  (bus_entry (at 97.79 137.16) (size 2.54 -2.54)
    (stroke (width 0) (type default))
  )
  (bus_entry (at 34.29 134.62) (size -2.54 -2.54)
    (stroke (width 0) (type default))
  )
  (bus_entry (at 34.29 132.08) (size -2.54 -2.54)
    (stroke (width 0) (type default))
  )
  (bus_entry (at 196.85 76.2) (size -2.54 2.54)
    (stroke (width 0) (type default))
  )
  (bus_entry (at 129.54 132.08) (size -2.54 -2.54)
    (stroke (width 0) (type default))
  )
  (bus_entry (at 194.31 76.2) (size 2.54 -2.54)
    (stroke (width 0) (type default))
  )
  (bus_entry (at 129.54 124.46) (size -2.54 -2.54)
    (stroke (width 0) (type default))
  )
  (bus_entry (at 129.54 121.92) (size -2.54 -2.54)
    (stroke (width 0) (type default))
  )
  (bus_entry (at 34.29 129.54) (size -2.54 -2.54)
    (stroke (width 0) (type default))
  )
  (bus_entry (at 196.85 71.12) (size -2.54 2.54)
    (stroke (width 0) (type default))
  )
  (bus_entry (at 105.41 78.74) (size 2.54 -2.54)
    (stroke (width 0) (type default))
  )
  (bus_entry (at 127 96.52) (size 2.54 2.54)
    (stroke (width 0) (type default))
  )
  (bus_entry (at 34.29 124.46) (size -2.54 -2.54)
    (stroke (width 0) (type default))
  )
  (bus_entry (at 194.31 124.46) (size 2.54 -2.54)
    (stroke (width 0) (type default))
  )
  (bus_entry (at 97.79 134.62) (size 2.54 -2.54)
    (stroke (width 0) (type default))
  )
  (bus_entry (at 129.54 134.62) (size -2.54 -2.54)
    (stroke (width 0) (type default))
  )
  (bus_entry (at 194.31 116.84) (size 2.54 -2.54)
    (stroke (width 0) (type default))
  )
  (bus_entry (at 128.27 76.2) (size 2.54 2.54)
    (stroke (width 0) (type default))
  )
  (bus_entry (at 30.48 63.5) (size 2.54 2.54)
    (stroke (width 0) (type default))
  )
  (bus_entry (at 129.54 101.6) (size -2.54 -2.54)
    (stroke (width 0) (type default))
  )
  (bus_entry (at 129.54 119.38) (size -2.54 -2.54)
    (stroke (width 0) (type default))
  )
  (bus_entry (at 34.29 119.38) (size -2.54 -2.54)
    (stroke (width 0) (type default))
  )
  (bus_entry (at 196.85 104.14) (size -2.54 2.54)
    (stroke (width 0) (type default))
  )

  (wire (pts (xy 80.01 149.86) (xy 91.44 149.86))
    (stroke (width 0) (type default))
  )
  (wire (pts (xy 88.265 230.505) (xy 88.9 230.505))
    (stroke (width 0) (type default))
  )
  (wire (pts (xy 129.54 124.46) (xy 148.59 124.46))
    (stroke (width 0) (type default))
  )
  (wire (pts (xy 245.11 167.64) (xy 245.11 176.53))
    (stroke (width 0) (type default))
  )
  (wire (pts (xy 130.81 78.74) (xy 148.59 78.74))
    (stroke (width 0) (type default))
  )
  (wire (pts (xy 302.26 86.36) (xy 275.59 86.36))
    (stroke (width 0) (type default))
  )
  (wire (pts (xy 176.53 167.64) (xy 187.96 167.64))
    (stroke (width 0) (type default))
  )
  (wire (pts (xy 340.36 116.84) (xy 344.17 116.84))
    (stroke (width 0) (type default))
  )
  (wire (pts (xy 19.685 192.405) (xy 59.055 192.405))
    (stroke (width 0) (type default))
  )
  (wire (pts (xy 372.11 96.52) (xy 375.92 96.52))
    (stroke (width 0) (type default))
  )
  (wire (pts (xy 34.29 124.46) (xy 52.07 124.46))
    (stroke (width 0) (type default))
  )
  (wire (pts (xy 317.5 114.3) (xy 344.17 114.3))
    (stroke (width 0) (type default))
  )
  (wire (pts (xy 340.36 109.22) (xy 340.36 116.84))
    (stroke (width 0) (type default))
  )
  (bus (pts (xy 196.85 73.66) (xy 196.85 76.2))
    (stroke (width 0) (type default))
  )

  (wire (pts (xy 52.07 137.16) (xy 50.165 137.16))
    (stroke (width 0) (type default))
  )
  (wire (pts (xy 375.92 104.14) (xy 375.92 111.76))
    (stroke (width 0) (type default))
  )
  (bus (pts (xy 30.48 124.46) (xy 31.75 124.46))
    (stroke (width 0) (type default))
  )

  (wire (pts (xy 19.685 25.4) (xy 19.685 26.67))
    (stroke (width 0) (type default))
  )
  (bus (pts (xy 196.85 127) (xy 196.85 132.08))
    (stroke (width 0) (type default))
  )

  (wire (pts (xy 176.53 142.24) (xy 180.34 142.24))
    (stroke (width 0) (type default))
  )
  (wire (pts (xy 176.53 43.18) (xy 187.96 43.18))
    (stroke (width 0) (type default))
  )
  (wire (pts (xy 80.01 175.26) (xy 88.9 175.26))
    (stroke (width 0) (type default))
  )
  (wire (pts (xy 245.11 63.5) (xy 247.65 63.5))
    (stroke (width 0) (type default))
  )
  (wire (pts (xy 52.07 152.4) (xy 40.64 152.4))
    (stroke (width 0) (type default))
  )
  (wire (pts (xy 203.962 86.36) (xy 176.53 86.36))
    (stroke (width 0) (type default))
  )
  (wire (pts (xy 404.114 109.22) (xy 372.11 109.22))
    (stroke (width 0) (type default))
  )
  (wire (pts (xy 146.05 58.42) (xy 148.59 58.42))
    (stroke (width 0) (type default))
  )
  (wire (pts (xy 50.165 137.16) (xy 50.165 139.7))
    (stroke (width 0) (type default))
  )
  (wire (pts (xy 148.59 144.78) (xy 137.16 144.78))
    (stroke (width 0) (type default))
  )
  (bus (pts (xy 196.85 71.12) (xy 196.85 73.66))
    (stroke (width 0) (type default))
  )

  (wire (pts (xy 317.5 96.52) (xy 344.17 96.52))
    (stroke (width 0) (type default))
  )
  (wire (pts (xy 80.01 63.5) (xy 104.14 63.5))
    (stroke (width 0) (type default))
  )
  (wire (pts (xy 317.5 119.38) (xy 344.17 119.38))
    (stroke (width 0) (type default))
  )
  (wire (pts (xy 80.01 104.14) (xy 91.44 104.14))
    (stroke (width 0) (type default))
  )
  (wire (pts (xy 88.265 196.85) (xy 99.695 196.85))
    (stroke (width 0) (type default))
  )
  (wire (pts (xy 278.13 111.76) (xy 278.13 119.38))
    (stroke (width 0) (type default))
  )
  (wire (pts (xy 180.34 30.48) (xy 176.53 30.48))
    (stroke (width 0) (type default))
  )
  (wire (pts (xy 19.685 197.485) (xy 41.275 197.485))
    (stroke (width 0) (type default))
  )
  (wire (pts (xy 25.4 93.98) (xy 52.07 93.98))
    (stroke (width 0) (type default))
  )
  (wire (pts (xy 317.5 162.56) (xy 344.17 162.56))
    (stroke (width 0) (type default))
  )
  (wire (pts (xy 302.26 134.62) (xy 275.59 134.62))
    (stroke (width 0) (type default))
  )
  (wire (pts (xy 50.165 35.56) (xy 50.165 43.18))
    (stroke (width 0) (type default))
  )
  (wire (pts (xy 404.114 71.12) (xy 372.11 71.12))
    (stroke (width 0) (type default))
  )
  (wire (pts (xy 141.605 205.74) (xy 141.605 213.36))
    (stroke (width 0) (type default))
  )
  (wire (pts (xy 340.36 71.12) (xy 344.17 71.12))
    (stroke (width 0) (type default))
  )
  (wire (pts (xy 148.59 68.58) (xy 130.81 68.58))
    (stroke (width 0) (type default))
  )
  (wire (pts (xy 340.36 132.08) (xy 344.17 132.08))
    (stroke (width 0) (type default))
  )
  (wire (pts (xy 81.915 154.94) (xy 81.915 162.56))
    (stroke (width 0) (type default))
  )
  (wire (pts (xy 176.53 147.32) (xy 187.96 147.32))
    (stroke (width 0) (type default))
  )
  (wire (pts (xy 148.59 165.1) (xy 121.92 165.1))
    (stroke (width 0) (type default))
  )
  (wire (pts (xy 245.11 63.5) (xy 245.11 71.12))
    (stroke (width 0) (type default))
  )
  (wire (pts (xy 129.54 111.76) (xy 148.59 111.76))
    (stroke (width 0) (type default))
  )
  (wire (pts (xy 148.59 142.24) (xy 137.16 142.24))
    (stroke (width 0) (type default))
  )
  (bus (pts (xy 127 105.41) (xy 127 106.68))
    (stroke (width 0) (type default))
  )

  (wire (pts (xy 247.65 60.96) (xy 224.282 60.96))
    (stroke (width 0) (type default))
  )
  (wire (pts (xy 176.53 83.82) (xy 203.962 83.82))
    (stroke (width 0) (type default))
  )
  (wire (pts (xy 81.915 53.34) (xy 81.915 60.96))
    (stroke (width 0) (type default))
  )
  (wire (pts (xy 404.114 154.94) (xy 372.11 154.94))
    (stroke (width 0) (type default))
  )
  (wire (pts (xy 314.96 222.25) (xy 304.8 222.25))
    (stroke (width 0) (type default))
  )
  (wire (pts (xy 404.114 53.34) (xy 372.11 53.34))
    (stroke (width 0) (type default))
  )
  (wire (pts (xy 275.59 127) (xy 278.13 127))
    (stroke (width 0) (type default))
  )
  (wire (pts (xy 317.5 58.42) (xy 344.17 58.42))
    (stroke (width 0) (type default))
  )
  (wire (pts (xy 52.07 33.02) (xy 40.64 33.02))
    (stroke (width 0) (type default))
  )
  (wire (pts (xy 302.26 121.92) (xy 275.59 121.92))
    (stroke (width 0) (type default))
  )
  (wire (pts (xy 404.114 99.06) (xy 372.11 99.06))
    (stroke (width 0) (type default))
  )
  (wire (pts (xy 146.05 116.84) (xy 146.05 127))
    (stroke (width 0) (type default))
  )
  (wire (pts (xy 146.05 43.18) (xy 146.05 50.8))
    (stroke (width 0) (type default))
  )
  (wire (pts (xy 148.59 104.14) (xy 121.666 104.14))
    (stroke (width 0) (type default))
  )
  (wire (pts (xy 372.11 73.66) (xy 375.92 73.66))
    (stroke (width 0) (type default))
  )
  (wire (pts (xy 372.11 152.4) (xy 375.92 152.4))
    (stroke (width 0) (type default))
  )
  (wire (pts (xy 257.175 265.43) (xy 258.445 265.43))
    (stroke (width 0) (type default))
  )
  (wire (pts (xy 278.13 152.4) (xy 278.13 162.56))
    (stroke (width 0) (type default))
  )
  (wire (pts (xy 375.92 30.48) (xy 375.92 33.02))
    (stroke (width 0) (type default))
  )
  (wire (pts (xy 52.07 149.86) (xy 50.165 149.86))
    (stroke (width 0) (type default))
  )
  (wire (pts (xy 275.59 30.48) (xy 278.13 30.48))
    (stroke (width 0) (type default))
  )
  (wire (pts (xy 267.97 222.25) (xy 267.97 223.52))
    (stroke (width 0) (type default))
  )
  (wire (pts (xy 317.5 121.92) (xy 344.17 121.92))
    (stroke (width 0) (type default))
  )
  (wire (pts (xy 245.11 116.84) (xy 247.65 116.84))
    (stroke (width 0) (type default))
  )
  (wire (pts (xy 32.385 200.025) (xy 32.385 203.2))
    (stroke (width 0) (type default))
  )
  (wire (pts (xy 52.07 172.72) (xy 45.72 172.72))
    (stroke (width 0) (type default))
  )
  (wire (pts (xy 52.07 35.56) (xy 50.165 35.56))
    (stroke (width 0) (type default))
  )
  (wire (pts (xy 247.65 99.06) (xy 224.282 99.06))
    (stroke (width 0) (type default))
  )
  (wire (pts (xy 80.01 127) (xy 97.79 127))
    (stroke (width 0) (type default))
  )
  (wire (pts (xy 52.07 68.58) (xy 50.165 68.58))
    (stroke (width 0) (type default))
  )
  (wire (pts (xy 116.205 196.85) (xy 127.635 196.85))
    (stroke (width 0) (type default))
  )
  (wire (pts (xy 247.65 96.52) (xy 224.282 96.52))
    (stroke (width 0) (type default))
  )
  (wire (pts (xy 52.07 48.26) (xy 25.4 48.26))
    (stroke (width 0) (type default))
  )
  (wire (pts (xy 50.165 68.58) (xy 50.165 76.2))
    (stroke (width 0) (type default))
  )
  (bus (pts (xy 127 109.22) (xy 127 111.76))
    (stroke (width 0) (type default))
  )

  (wire (pts (xy 317.5 111.76) (xy 344.17 111.76))
    (stroke (width 0) (type default))
  )
  (wire (pts (xy 146.05 96.52) (xy 148.59 96.52))
    (stroke (width 0) (type default))
  )
  (wire (pts (xy 326.39 196.85) (xy 314.96 196.85))
    (stroke (width 0) (type default))
  )
  (wire (pts (xy 257.81 223.52) (xy 257.81 222.25))
    (stroke (width 0) (type default))
  )
  (wire (pts (xy 224.282 152.4) (xy 247.65 152.4))
    (stroke (width 0) (type default))
  )
  (wire (pts (xy 278.13 33.02) (xy 278.13 40.64))
    (stroke (width 0) (type default))
  )
  (wire (pts (xy 80.01 78.74) (xy 105.41 78.74))
    (stroke (width 0) (type default))
  )
  (wire (pts (xy 133.985 175.26) (xy 144.145 175.26))
    (stroke (width 0) (type default))
  )
  (wire (pts (xy 317.246 50.8) (xy 344.17 50.8))
    (stroke (width 0) (type default))
  )
  (wire (pts (xy 148.59 196.85) (xy 155.575 196.85))
    (stroke (width 0) (type default))
  )
  (wire (pts (xy 155.575 196.85) (xy 160.02 196.85))
    (stroke (width 0) (type default))
  )
  (wire (pts (xy 176.53 93.98) (xy 194.056 93.98))
    (stroke (width 0) (type default))
  )
  (wire (pts (xy 34.29 119.38) (xy 52.07 119.38))
    (stroke (width 0) (type default))
  )
  (wire (pts (xy 81.915 111.76) (xy 80.01 111.76))
    (stroke (width 0) (type default))
  )
  (wire (pts (xy 146.05 160.02) (xy 146.05 167.64))
    (stroke (width 0) (type default))
  )
  (wire (pts (xy 50.165 43.18) (xy 50.165 50.8))
    (stroke (width 0) (type default))
  )
  (wire (pts (xy 176.53 88.9) (xy 203.962 88.9))
    (stroke (width 0) (type default))
  )
  (wire (pts (xy 372.11 162.56) (xy 375.92 162.56))
    (stroke (width 0) (type default))
  )
  (wire (pts (xy 148.59 160.02) (xy 146.05 160.02))
    (stroke (width 0) (type default))
  )
  (wire (pts (xy 302.26 60.96) (xy 275.59 60.96))
    (stroke (width 0) (type default))
  )
  (wire (pts (xy 148.59 162.56) (xy 121.92 162.56))
    (stroke (width 0) (type default))
  )
  (wire (pts (xy 81.915 101.6) (xy 80.01 101.6))
    (stroke (width 0) (type default))
  )
  (bus (pts (xy 196.85 109.22) (xy 196.85 111.76))
    (stroke (width 0) (type default))
  )
  (bus (pts (xy 31.75 129.54) (xy 31.75 132.08))
    (stroke (width 0) (type default))
  )

  (wire (pts (xy 146.05 25.4) (xy 146.05 27.94))
    (stroke (width 0) (type default))
  )
  (bus (pts (xy 127 105.41) (xy 125.73 105.41))
    (stroke (width 0) (type default))
  )

  (wire (pts (xy 245.11 137.16) (xy 245.11 147.32))
    (stroke (width 0) (type default))
  )
  (wire (pts (xy 176.53 114.3) (xy 194.31 114.3))
    (stroke (width 0) (type default))
  )
  (wire (pts (xy 247.65 38.1) (xy 245.11 38.1))
    (stroke (width 0) (type default))
  )
  (wire (pts (xy 19.685 200.025) (xy 32.385 200.025))
    (stroke (width 0) (type default))
  )
  (wire (pts (xy 404.114 45.72) (xy 372.11 45.72))
    (stroke (width 0) (type default))
  )
  (wire (pts (xy 372.11 104.14) (xy 375.92 104.14))
    (stroke (width 0) (type default))
  )
  (wire (pts (xy 80.01 76.2) (xy 93.472 76.2))
    (stroke (width 0) (type default))
  )
  (wire (pts (xy 148.59 147.32) (xy 146.05 147.32))
    (stroke (width 0) (type default))
  )
  (bus (pts (xy 196.85 93.98) (xy 196.85 96.52))
    (stroke (width 0) (type default))
  )

  (wire (pts (xy 245.11 86.36) (xy 245.11 93.98))
    (stroke (width 0) (type default))
  )
  (wire (pts (xy 278.13 162.56) (xy 278.13 176.53))
    (stroke (width 0) (type default))
  )
  (wire (pts (xy 148.59 66.04) (xy 146.05 66.04))
    (stroke (width 0) (type default))
  )
  (wire (pts (xy 52.07 160.02) (xy 50.165 160.02))
    (stroke (width 0) (type default))
  )
  (wire (pts (xy 224.282 142.24) (xy 247.65 142.24))
    (stroke (width 0) (type default))
  )
  (wire (pts (xy 81.915 71.12) (xy 81.915 81.28))
    (stroke (width 0) (type default))
  )
  (wire (pts (xy 129.54 109.22) (xy 148.59 109.22))
    (stroke (width 0) (type default))
  )
  (wire (pts (xy 59.055 208.28) (xy 59.055 212.725))
    (stroke (width 0) (type default))
  )
  (wire (pts (xy 372.11 50.8) (xy 375.92 50.8))
    (stroke (width 0) (type default))
  )
  (wire (pts (xy 127.635 213.36) (xy 134.62 213.36))
    (stroke (width 0) (type default))
  )
  (wire (pts (xy 340.36 93.98) (xy 344.17 93.98))
    (stroke (width 0) (type default))
  )
  (wire (pts (xy 50.165 176.53) (xy 50.165 170.18))
    (stroke (width 0) (type default))
  )
  (wire (pts (xy 278.13 96.52) (xy 278.13 104.14))
    (stroke (width 0) (type default))
  )
  (wire (pts (xy 129.54 132.08) (xy 148.59 132.08))
    (stroke (width 0) (type default))
  )
  (bus (pts (xy 196.85 91.44) (xy 196.85 93.98))
    (stroke (width 0) (type default))
  )

  (wire (pts (xy 148.59 55.88) (xy 125.095 55.88))
    (stroke (width 0) (type default))
  )
  (bus (pts (xy 127 114.3) (xy 125.73 114.3))
    (stroke (width 0) (type default))
  )

  (wire (pts (xy 116.205 213.36) (xy 116.205 207.01))
    (stroke (width 0) (type default))
  )
  (wire (pts (xy 245.11 55.88) (xy 245.11 63.5))
    (stroke (width 0) (type default))
  )
  (wire (pts (xy 340.36 78.74) (xy 344.17 78.74))
    (stroke (width 0) (type default))
  )
  (wire (pts (xy 155.575 196.85) (xy 155.575 200.66))
    (stroke (width 0) (type default))
  )
  (wire (pts (xy 245.11 132.08) (xy 247.65 132.08))
    (stroke (width 0) (type default))
  )
  (wire (pts (xy 375.92 58.42) (xy 375.92 66.04))
    (stroke (width 0) (type default))
  )
  (wire (pts (xy 275.59 162.56) (xy 278.13 162.56))
    (stroke (width 0) (type default))
  )
  (wire (pts (xy 50.165 88.9) (xy 50.165 106.68))
    (stroke (width 0) (type default))
  )
  (wire (pts (xy 278.13 40.64) (xy 278.13 43.18))
    (stroke (width 0) (type default))
  )
  (wire (pts (xy 146.05 139.7) (xy 146.05 147.32))
    (stroke (width 0) (type default))
  )
  (wire (pts (xy 404.114 38.1) (xy 372.11 38.1))
    (stroke (width 0) (type default))
  )
  (wire (pts (xy 146.05 170.18) (xy 146.05 176.53))
    (stroke (width 0) (type default))
  )
  (wire (pts (xy 34.29 129.54) (xy 52.07 129.54))
    (stroke (width 0) (type default))
  )
  (wire (pts (xy 52.07 78.74) (xy 40.64 78.74))
    (stroke (width 0) (type default))
  )
  (wire (pts (xy 81.915 101.6) (xy 81.915 111.76))
    (stroke (width 0) (type default))
  )
  (wire (pts (xy 317.5 172.72) (xy 344.17 172.72))
    (stroke (width 0) (type default))
  )
  (wire (pts (xy 340.36 48.26) (xy 340.36 55.88))
    (stroke (width 0) (type default))
  )
  (bus (pts (xy 100.33 121.92) (xy 100.33 124.46))
    (stroke (width 0) (type default))
  )

  (wire (pts (xy 52.07 142.24) (xy 40.64 142.24))
    (stroke (width 0) (type default))
  )
  (wire (pts (xy 275.59 152.4) (xy 278.13 152.4))
    (stroke (width 0) (type default))
  )
  (wire (pts (xy 404.114 149.86) (xy 372.11 149.86))
    (stroke (width 0) (type default))
  )
  (wire (pts (xy 372.11 81.28) (xy 375.92 81.28))
    (stroke (width 0) (type default))
  )
  (bus (pts (xy 196.85 102.87) (xy 196.85 104.14))
    (stroke (width 0) (type default))
  )

  (wire (pts (xy 52.07 71.12) (xy 40.64 71.12))
    (stroke (width 0) (type default))
  )
  (wire (pts (xy 121.92 271.145) (xy 121.92 269.875))
    (stroke (width 0) (type default))
  )
  (wire (pts (xy 245.11 124.46) (xy 247.65 124.46))
    (stroke (width 0) (type default))
  )
  (wire (pts (xy 317.5 33.02) (xy 344.17 33.02))
    (stroke (width 0) (type default))
  )
  (wire (pts (xy 52.07 58.42) (xy 50.165 58.42))
    (stroke (width 0) (type default))
  )
  (wire (pts (xy 302.26 71.12) (xy 275.59 71.12))
    (stroke (width 0) (type default))
  )
  (wire (pts (xy 356.235 205.74) (xy 386.08 205.74))
    (stroke (width 0) (type default))
  )
  (wire (pts (xy 148.59 154.94) (xy 137.16 154.94))
    (stroke (width 0) (type default))
  )
  (wire (pts (xy 121.92 278.765) (xy 120.65 278.765))
    (stroke (width 0) (type default))
  )
  (wire (pts (xy 245.11 196.85) (xy 247.65 196.85))
    (stroke (width 0) (type default))
  )
  (bus (pts (xy 127 124.46) (xy 127 127))
    (stroke (width 0) (type default))
  )

  (wire (pts (xy 50.165 212.725) (xy 59.055 212.725))
    (stroke (width 0) (type default))
  )
  (wire (pts (xy 275.59 58.42) (xy 278.13 58.42))
    (stroke (width 0) (type default))
  )
  (wire (pts (xy 372.11 165.1) (xy 404.114 165.1))
    (stroke (width 0) (type default))
  )
  (wire (pts (xy 247.65 76.2) (xy 224.282 76.2))
    (stroke (width 0) (type default))
  )
  (wire (pts (xy 247.65 45.72) (xy 245.11 45.72))
    (stroke (width 0) (type default))
  )
  (wire (pts (xy 176.53 101.6) (xy 180.34 101.6))
    (stroke (width 0) (type default))
  )
  (wire (pts (xy 81.915 91.44) (xy 80.01 91.44))
    (stroke (width 0) (type default))
  )
  (wire (pts (xy 81.915 60.96) (xy 81.915 71.12))
    (stroke (width 0) (type default))
  )
  (wire (pts (xy 224.282 172.72) (xy 247.65 172.72))
    (stroke (width 0) (type default))
  )
  (wire (pts (xy 245.11 86.36) (xy 247.65 86.36))
    (stroke (width 0) (type default))
  )
  (wire (pts (xy 317.5 60.96) (xy 344.17 60.96))
    (stroke (width 0) (type default))
  )
  (wire (pts (xy 170.815 205.74) (xy 169.545 205.74))
    (stroke (width 0) (type default))
  )
  (wire (pts (xy 247.65 104.14) (xy 224.282 104.14))
    (stroke (width 0) (type default))
  )
  (wire (pts (xy 224.282 170.18) (xy 247.65 170.18))
    (stroke (width 0) (type default))
  )
  (wire (pts (xy 247.65 43.18) (xy 224.282 43.18))
    (stroke (width 0) (type default))
  )
  (wire (pts (xy 267.97 196.85) (xy 278.13 196.85))
    (stroke (width 0) (type default))
  )
  (wire (pts (xy 80.01 96.52) (xy 91.44 96.52))
    (stroke (width 0) (type default))
  )
  (wire (pts (xy 317.5 165.1) (xy 344.17 165.1))
    (stroke (width 0) (type default))
  )
  (wire (pts (xy 340.36 48.26) (xy 344.17 48.26))
    (stroke (width 0) (type default))
  )
  (wire (pts (xy 176.53 66.04) (xy 187.96 66.04))
    (stroke (width 0) (type default))
  )
  (wire (pts (xy 375.92 142.24) (xy 375.92 152.4))
    (stroke (width 0) (type default))
  )
  (wire (pts (xy 245.11 93.98) (xy 245.11 101.6))
    (stroke (width 0) (type default))
  )
  (wire (pts (xy 146.05 139.7) (xy 148.59 139.7))
    (stroke (width 0) (type default))
  )
  (wire (pts (xy 314.96 196.85) (xy 304.8 196.85))
    (stroke (width 0) (type default))
  )
  (wire (pts (xy 317.5 68.58) (xy 344.17 68.58))
    (stroke (width 0) (type default))
  )
  (wire (pts (xy 372.11 58.42) (xy 375.92 58.42))
    (stroke (width 0) (type default))
  )
  (wire (pts (xy 372.11 175.26) (xy 404.495 175.26))
    (stroke (width 0) (type default))
  )
  (wire (pts (xy 278.13 222.25) (xy 278.13 223.52))
    (stroke (width 0) (type default))
  )
  (wire (pts (xy 176.53 175.26) (xy 184.15 175.26))
    (stroke (width 0) (type default))
  )
  (wire (pts (xy 52.07 43.18) (xy 50.165 43.18))
    (stroke (width 0) (type default))
  )
  (wire (pts (xy 134.62 213.36) (xy 141.605 213.36))
    (stroke (width 0) (type default))
  )
  (wire (pts (xy 165.1 196.85) (xy 169.545 196.85))
    (stroke (width 0) (type default))
  )
  (wire (pts (xy 81.915 142.24) (xy 81.915 144.78))
    (stroke (width 0) (type default))
  )
  (wire (pts (xy 372.11 167.64) (xy 404.114 167.64))
    (stroke (width 0) (type default))
  )
  (wire (pts (xy 278.13 58.42) (xy 278.13 66.04))
    (stroke (width 0) (type default))
  )
  (wire (pts (xy 375.92 111.76) (xy 375.92 119.38))
    (stroke (width 0) (type default))
  )
  (wire (pts (xy 176.53 27.94) (xy 180.34 27.94))
    (stroke (width 0) (type default))
  )
  (wire (pts (xy 113.665 196.85) (xy 116.205 196.85))
    (stroke (width 0) (type default))
  )
  (wire (pts (xy 81.915 152.4) (xy 81.915 154.94))
    (stroke (width 0) (type default))
  )
  (wire (pts (xy 80.01 25.4) (xy 91.44 25.4))
    (stroke (width 0) (type default))
  )
  (wire (pts (xy 247.65 66.04) (xy 224.282 66.04))
    (stroke (width 0) (type default))
  )
  (wire (pts (xy 148.59 83.82) (xy 130.81 83.82))
    (stroke (width 0) (type default))
  )
  (wire (pts (xy 247.65 223.52) (xy 247.65 222.25))
    (stroke (width 0) (type default))
  )
  (wire (pts (xy 176.53 25.4) (xy 180.34 25.4))
    (stroke (width 0) (type default))
  )
  (bus (pts (xy 30.48 62.23) (xy 30.48 63.5))
    (stroke (width 0) (type default))
  )

  (wire (pts (xy 148.59 35.56) (xy 146.05 35.56))
    (stroke (width 0) (type default))
  )
  (wire (pts (xy 85.09 58.42) (xy 85.09 55.88))
    (stroke (width 0) (type default))
  )
  (wire (pts (xy 245.11 38.1) (xy 245.11 45.72))
    (stroke (width 0) (type default))
  )
  (wire (pts (xy 129.54 99.06) (xy 148.59 99.06))
    (stroke (width 0) (type default))
  )
  (wire (pts (xy 148.59 152.4) (xy 137.16 152.4))
    (stroke (width 0) (type default))
  )
  (wire (pts (xy 247.65 119.38) (xy 224.282 119.38))
    (stroke (width 0) (type default))
  )
  (wire (pts (xy 340.36 55.88) (xy 344.17 55.88))
    (stroke (width 0) (type default))
  )
  (wire (pts (xy 375.92 127) (xy 375.92 132.08))
    (stroke (width 0) (type default))
  )
  (wire (pts (xy 176.53 33.02) (xy 187.96 33.02))
    (stroke (width 0) (type default))
  )
  (wire (pts (xy 317.5 175.26) (xy 344.17 175.26))
    (stroke (width 0) (type default))
  )
  (wire (pts (xy 146.05 35.56) (xy 146.05 43.18))
    (stroke (width 0) (type default))
  )
  (wire (pts (xy 120.65 253.365) (xy 121.92 253.365))
    (stroke (width 0) (type default))
  )
  (wire (pts (xy 52.07 38.1) (xy 25.4 38.1))
    (stroke (width 0) (type default))
  )
  (wire (pts (xy 121.92 280.035) (xy 121.92 278.765))
    (stroke (width 0) (type default))
  )
  (bus (pts (xy 196.85 121.92) (xy 196.85 124.46))
    (stroke (width 0) (type default))
  )
  (bus (pts (xy 198.12 102.87) (xy 196.85 102.87))
    (stroke (width 0) (type default))
  )

  (wire (pts (xy 302.26 154.94) (xy 275.59 154.94))
    (stroke (width 0) (type default))
  )
  (wire (pts (xy 404.114 144.78) (xy 372.11 144.78))
    (stroke (width 0) (type default))
  )
  (wire (pts (xy 340.36 38.1) (xy 340.36 45.72))
    (stroke (width 0) (type default))
  )
  (wire (pts (xy 148.59 45.72) (xy 136.525 45.72))
    (stroke (width 0) (type default))
  )
  (bus (pts (xy 196.85 114.3) (xy 196.85 116.84))
    (stroke (width 0) (type default))
  )

  (wire (pts (xy 80.01 73.66) (xy 105.41 73.66))
    (stroke (width 0) (type default))
  )
  (wire (pts (xy 146.05 106.68) (xy 146.05 116.84))
    (stroke (width 0) (type default))
  )
  (wire (pts (xy 52.07 60.96) (xy 40.64 60.96))
    (stroke (width 0) (type default))
  )
  (wire (pts (xy 169.545 203.2) (xy 170.815 203.2))
    (stroke (width 0) (type default))
  )
  (wire (pts (xy 80.01 124.46) (xy 97.79 124.46))
    (stroke (width 0) (type default))
  )
  (wire (pts (xy 375.92 33.02) (xy 375.92 40.64))
    (stroke (width 0) (type default))
  )
  (wire (pts (xy 50.165 194.945) (xy 50.165 203.2))
    (stroke (width 0) (type default))
  )
  (wire (pts (xy 146.05 167.64) (xy 146.05 170.18))
    (stroke (width 0) (type default))
  )
  (wire (pts (xy 146.05 50.8) (xy 148.59 50.8))
    (stroke (width 0) (type default))
  )
  (wire (pts (xy 59.055 192.405) (xy 59.055 203.2))
    (stroke (width 0) (type default))
  )
  (wire (pts (xy 52.07 114.3) (xy 40.64 114.3))
    (stroke (width 0) (type default))
  )
  (bus (pts (xy 196.85 91.44) (xy 198.12 91.44))
    (stroke (width 0) (type default))
  )

  (wire (pts (xy 169.545 196.85) (xy 169.545 203.2))
    (stroke (width 0) (type default))
  )
  (bus (pts (xy 196.85 69.85) (xy 198.12 69.85))
    (stroke (width 0) (type default))
  )

  (wire (pts (xy 41.275 212.725) (xy 50.165 212.725))
    (stroke (width 0) (type default))
  )
  (wire (pts (xy 224.282 165.1) (xy 247.65 165.1))
    (stroke (width 0) (type default))
  )
  (polyline (pts (xy 77.47 181.61) (xy 77.47 246.38))
    (stroke (width 0) (type default))
  )

  (wire (pts (xy 317.5 152.4) (xy 344.17 152.4))
    (stroke (width 0) (type default))
  )
  (bus (pts (xy 31.75 119.38) (xy 31.75 121.92))
    (stroke (width 0) (type default))
  )

  (wire (pts (xy 176.53 116.84) (xy 194.31 116.84))
    (stroke (width 0) (type default))
  )
  (wire (pts (xy 19.685 194.945) (xy 50.165 194.945))
    (stroke (width 0) (type default))
  )
  (wire (pts (xy 127.635 196.85) (xy 127.635 200.66))
    (stroke (width 0) (type default))
  )
  (polyline (pts (xy 12.065 181.61) (xy 407.035 181.61))
    (stroke (width 0) (type default))
  )

  (wire (pts (xy 340.36 137.16) (xy 344.17 137.16))
    (stroke (width 0) (type default))
  )
  (wire (pts (xy 146.05 127) (xy 146.05 139.7))
    (stroke (width 0) (type default))
  )
  (bus (pts (xy 127 106.68) (xy 127 109.22))
    (stroke (width 0) (type default))
  )

  (wire (pts (xy 317.5 53.34) (xy 344.17 53.34))
    (stroke (width 0) (type default))
  )
  (wire (pts (xy 372.11 88.9) (xy 375.92 88.9))
    (stroke (width 0) (type default))
  )
  (wire (pts (xy 50.165 58.42) (xy 50.165 68.58))
    (stroke (width 0) (type default))
  )
  (wire (pts (xy 80.01 137.16) (xy 97.79 137.16))
    (stroke (width 0) (type default))
  )
  (wire (pts (xy 80.01 165.1) (xy 81.915 165.1))
    (stroke (width 0) (type default))
  )
  (wire (pts (xy 375.92 162.56) (xy 375.92 176.53))
    (stroke (width 0) (type default))
  )
  (wire (pts (xy 275.59 88.9) (xy 278.13 88.9))
    (stroke (width 0) (type default))
  )
  (wire (pts (xy 404.114 55.88) (xy 372.11 55.88))
    (stroke (width 0) (type default))
  )
  (polyline (pts (xy 344.805 246.38) (xy 344.805 181.61))
    (stroke (width 0) (type default))
  )

  (wire (pts (xy 148.59 213.36) (xy 155.575 213.36))
    (stroke (width 0) (type default))
  )
  (wire (pts (xy 88.265 196.85) (xy 86.995 196.85))
    (stroke (width 0) (type default))
  )
  (wire (pts (xy 50.165 76.2) (xy 50.165 88.9))
    (stroke (width 0) (type default))
  )
  (wire (pts (xy 278.13 132.08) (xy 278.13 142.24))
    (stroke (width 0) (type default))
  )
  (wire (pts (xy 52.07 27.94) (xy 50.165 27.94))
    (stroke (width 0) (type default))
  )
  (wire (pts (xy 81.915 132.08) (xy 80.01 132.08))
    (stroke (width 0) (type default))
  )
  (wire (pts (xy 176.53 60.96) (xy 180.34 60.96))
    (stroke (width 0) (type default))
  )
  (wire (pts (xy 176.53 137.16) (xy 194.31 137.16))
    (stroke (width 0) (type default))
  )
  (wire (pts (xy 404.114 76.2) (xy 372.11 76.2))
    (stroke (width 0) (type default))
  )
  (bus (pts (xy 107.95 69.85) (xy 107.95 71.12))
    (stroke (width 0) (type default))
  )

  (wire (pts (xy 180.34 71.12) (xy 176.53 71.12))
    (stroke (width 0) (type default))
  )
  (wire (pts (xy 340.36 55.88) (xy 340.36 63.5))
    (stroke (width 0) (type default))
  )
  (wire (pts (xy 148.59 88.9) (xy 137.16 88.9))
    (stroke (width 0) (type default))
  )
  (wire (pts (xy 247.65 25.4) (xy 245.11 25.4))
    (stroke (width 0) (type default))
  )
  (wire (pts (xy 278.13 81.28) (xy 278.13 88.9))
    (stroke (width 0) (type default))
  )
  (bus (pts (xy 31.75 127) (xy 31.75 129.54))
    (stroke (width 0) (type default))
  )

  (wire (pts (xy 148.59 25.4) (xy 146.05 25.4))
    (stroke (width 0) (type default))
  )
  (wire (pts (xy 148.59 71.12) (xy 130.81 71.12))
    (stroke (width 0) (type default))
  )
  (bus (pts (xy 30.48 62.23) (xy 29.21 62.23))
    (stroke (width 0) (type default))
  )

  (wire (pts (xy 80.01 99.06) (xy 91.44 99.06))
    (stroke (width 0) (type default))
  )
  (wire (pts (xy 52.07 53.34) (xy 25.4 53.34))
    (stroke (width 0) (type default))
  )
  (wire (pts (xy 99.695 204.47) (xy 99.695 206.375))
    (stroke (width 0) (type default))
  )
  (wire (pts (xy 317.5 127) (xy 344.17 127))
    (stroke (width 0) (type default))
  )
  (wire (pts (xy 148.59 81.28) (xy 130.81 81.28))
    (stroke (width 0) (type default))
  )
  (wire (pts (xy 247.65 91.44) (xy 224.282 91.44))
    (stroke (width 0) (type default))
  )
  (wire (pts (xy 302.26 99.06) (xy 275.59 99.06))
    (stroke (width 0) (type default))
  )
  (bus (pts (xy 196.85 124.46) (xy 196.85 127))
    (stroke (width 0) (type default))
  )

  (wire (pts (xy 81.915 111.76) (xy 81.915 121.92))
    (stroke (width 0) (type default))
  )
  (bus (pts (xy 128.27 74.93) (xy 128.27 76.2))
    (stroke (width 0) (type default))
  )

  (wire (pts (xy 247.65 58.42) (xy 224.282 58.42))
    (stroke (width 0) (type default))
  )
  (bus (pts (xy 100.33 119.38) (xy 100.33 121.92))
    (stroke (width 0) (type default))
  )

  (wire (pts (xy 344.17 167.64) (xy 340.36 167.64))
    (stroke (width 0) (type default))
  )
  (wire (pts (xy 224.282 144.78) (xy 247.65 144.78))
    (stroke (width 0) (type default))
  )
  (bus (pts (xy 196.85 111.76) (xy 196.85 114.3))
    (stroke (width 0) (type default))
  )

  (wire (pts (xy 52.07 109.22) (xy 40.64 109.22))
    (stroke (width 0) (type default))
  )
  (wire (pts (xy 302.26 137.16) (xy 275.59 137.16))
    (stroke (width 0) (type default))
  )
  (wire (pts (xy 245.11 109.22) (xy 247.65 109.22))
    (stroke (width 0) (type default))
  )
  (wire (pts (xy 302.26 106.68) (xy 275.59 106.68))
    (stroke (width 0) (type default))
  )
  (wire (pts (xy 224.282 175.26) (xy 247.65 175.26))
    (stroke (width 0) (type default))
  )
  (wire (pts (xy 340.36 93.98) (xy 340.36 101.6))
    (stroke (width 0) (type default))
  )
  (wire (pts (xy 317.5 149.86) (xy 344.17 149.86))
    (stroke (width 0) (type default))
  )
  (wire (pts (xy 146.05 96.52) (xy 146.05 106.68))
    (stroke (width 0) (type default))
  )
  (wire (pts (xy 340.36 124.46) (xy 340.36 132.08))
    (stroke (width 0) (type default))
  )
  (wire (pts (xy 404.114 101.6) (xy 372.11 101.6))
    (stroke (width 0) (type default))
  )
  (wire (pts (xy 245.11 71.12) (xy 247.65 71.12))
    (stroke (width 0) (type default))
  )
  (wire (pts (xy 176.53 134.62) (xy 194.31 134.62))
    (stroke (width 0) (type default))
  )
  (wire (pts (xy 275.59 33.02) (xy 278.13 33.02))
    (stroke (width 0) (type default))
  )
  (wire (pts (xy 50.165 149.86) (xy 50.165 157.48))
    (stroke (width 0) (type default))
  )
  (wire (pts (xy 129.54 119.38) (xy 148.59 119.38))
    (stroke (width 0) (type default))
  )
  (wire (pts (xy 176.53 124.46) (xy 194.31 124.46))
    (stroke (width 0) (type default))
  )
  (bus (pts (xy 196.85 76.2) (xy 196.85 77.47))
    (stroke (width 0) (type default))
  )

  (wire (pts (xy 176.53 73.66) (xy 194.31 73.66))
    (stroke (width 0) (type default))
  )
  (bus (pts (xy 31.75 114.3) (xy 31.75 116.84))
    (stroke (width 0) (type default))
  )

  (wire (pts (xy 176.53 172.72) (xy 180.34 172.72))
    (stroke (width 0) (type default))
  )
  (wire (pts (xy 176.53 170.18) (xy 187.96 170.18))
    (stroke (width 0) (type default))
  )
  (wire (pts (xy 247.65 68.58) (xy 224.282 68.58))
    (stroke (width 0) (type default))
  )
  (wire (pts (xy 302.26 116.84) (xy 275.59 116.84))
    (stroke (width 0) (type default))
  )
  (wire (pts (xy 278.13 73.66) (xy 275.59 73.66))
    (stroke (width 0) (type default))
  )
  (wire (pts (xy 340.36 147.32) (xy 344.17 147.32))
    (stroke (width 0) (type default))
  )
  (wire (pts (xy 146.05 86.36) (xy 148.59 86.36))
    (stroke (width 0) (type default))
  )
  (wire (pts (xy 141.605 213.36) (xy 148.59 213.36))
    (stroke (width 0) (type default))
  )
  (wire (pts (xy 302.26 144.78) (xy 275.59 144.78))
    (stroke (width 0) (type default))
  )
  (wire (pts (xy 317.5 91.44) (xy 344.17 91.44))
    (stroke (width 0) (type default))
  )
  (wire (pts (xy 146.05 167.64) (xy 148.59 167.64))
    (stroke (width 0) (type default))
  )
  (wire (pts (xy 129.54 121.92) (xy 148.59 121.92))
    (stroke (width 0) (type default))
  )
  (wire (pts (xy 302.26 170.18) (xy 275.59 170.18))
    (stroke (width 0) (type default))
  )
  (wire (pts (xy 404.114 147.32) (xy 372.11 147.32))
    (stroke (width 0) (type default))
  )
  (wire (pts (xy 42.545 175.26) (xy 45.72 175.26))
    (stroke (width 0) (type default))
  )
  (bus (pts (xy 107.95 69.85) (xy 109.22 69.85))
    (stroke (width 0) (type default))
  )
  (bus (pts (xy 196.85 69.85) (xy 196.85 71.12))
    (stroke (width 0) (type default))
  )

  (wire (pts (xy 302.26 48.26) (xy 275.59 48.26))
    (stroke (width 0) (type default))
  )
  (wire (pts (xy 176.53 55.88) (xy 197.612 55.88))
    (stroke (width 0) (type default))
  )
  (wire (pts (xy 302.26 53.34) (xy 275.59 53.34))
    (stroke (width 0) (type default))
  )
  (wire (pts (xy 302.26 63.5) (xy 275.59 63.5))
    (stroke (width 0) (type default))
  )
  (wire (pts (xy 52.07 144.78) (xy 40.64 144.78))
    (stroke (width 0) (type default))
  )
  (wire (pts (xy 375.92 152.4) (xy 375.92 162.56))
    (stroke (width 0) (type default))
  )
  (wire (pts (xy 245.11 109.22) (xy 245.11 116.84))
    (stroke (width 0) (type default))
  )
  (wire (pts (xy 340.36 86.36) (xy 340.36 93.98))
    (stroke (width 0) (type default))
  )
  (wire (pts (xy 278.13 88.9) (xy 278.13 96.52))
    (stroke (width 0) (type default))
  )
  (wire (pts (xy 80.01 157.48) (xy 91.44 157.48))
    (stroke (width 0) (type default))
  )
  (wire (pts (xy 404.114 68.58) (xy 372.11 68.58))
    (stroke (width 0) (type default))
  )
  (wire (pts (xy 247.65 129.54) (xy 224.282 129.54))
    (stroke (width 0) (type default))
  )
  (wire (pts (xy 129.54 101.6) (xy 148.59 101.6))
    (stroke (width 0) (type default))
  )
  (wire (pts (xy 146.05 86.36) (xy 146.05 96.52))
    (stroke (width 0) (type default))
  )
  (bus (pts (xy 127 95.25) (xy 127 96.52))
    (stroke (width 0) (type default))
  )

  (wire (pts (xy 302.26 114.3) (xy 275.59 114.3))
    (stroke (width 0) (type default))
  )
  (wire (pts (xy 50.165 208.28) (xy 50.165 212.725))
    (stroke (width 0) (type default))
  )
  (bus (pts (xy 31.75 124.46) (xy 31.75 127))
    (stroke (width 0) (type default))
  )

  (wire (pts (xy 247.65 50.8) (xy 224.282 50.8))
    (stroke (width 0) (type default))
  )
  (wire (pts (xy 41.275 197.485) (xy 41.275 203.2))
    (stroke (width 0) (type default))
  )
  (wire (pts (xy 52.07 73.66) (xy 40.64 73.66))
    (stroke (width 0) (type default))
  )
  (wire (pts (xy 340.36 137.16) (xy 340.36 147.32))
    (stroke (width 0) (type default))
  )
  (wire (pts (xy 267.97 222.25) (xy 278.13 222.25))
    (stroke (width 0) (type default))
  )
  (wire (pts (xy 80.01 48.26) (xy 104.14 48.26))
    (stroke (width 0) (type default))
  )
  (wire (pts (xy 317.5 142.24) (xy 344.17 142.24))
    (stroke (width 0) (type default))
  )
  (wire (pts (xy 302.26 167.64) (xy 275.59 167.64))
    (stroke (width 0) (type default))
  )
  (wire (pts (xy 153.035 260.985) (xy 151.765 260.985))
    (stroke (width 0) (type default))
  )
  (wire (pts (xy 224.282 149.86) (xy 247.65 149.86))
    (stroke (width 0) (type default))
  )
  (polyline (pts (xy 12.7 246.38) (xy 224.79 246.38))
    (stroke (width 0) (type default))
  )

  (wire (pts (xy 340.36 132.08) (xy 340.36 137.16))
    (stroke (width 0) (type default))
  )
  (wire (pts (xy 247.65 198.12) (xy 247.65 196.85))
    (stroke (width 0) (type default))
  )
  (wire (pts (xy 141.605 196.85) (xy 148.59 196.85))
    (stroke (width 0) (type default))
  )
  (wire (pts (xy 80.01 50.8) (xy 104.14 50.8))
    (stroke (width 0) (type default))
  )
  (wire (pts (xy 245.11 101.6) (xy 245.11 109.22))
    (stroke (width 0) (type default))
  )
  (polyline (pts (xy 77.47 246.634) (xy 77.47 284.734))
    (stroke (width 0) (type default))
  )

  (wire (pts (xy 187.96 50.8) (xy 176.53 50.8))
    (stroke (width 0) (type default))
  )
  (wire (pts (xy 356.235 218.44) (xy 386.08 218.44))
    (stroke (width 0) (type default))
  )
  (wire (pts (xy 81.915 81.28) (xy 80.01 81.28))
    (stroke (width 0) (type default))
  )
  (wire (pts (xy 404.114 83.82) (xy 372.11 83.82))
    (stroke (width 0) (type default))
  )
  (wire (pts (xy 375.92 40.64) (xy 375.92 43.18))
    (stroke (width 0) (type default))
  )
  (polyline (pts (xy 224.79 182.245) (xy 224.79 284.48))
    (stroke (width 0) (type default))
  )

  (wire (pts (xy 104.775 206.375) (xy 104.775 204.47))
    (stroke (width 0) (type default))
  )
  (wire (pts (xy 180.34 53.34) (xy 176.53 53.34))
    (stroke (width 0) (type default))
  )
  (wire (pts (xy 375.92 132.08) (xy 375.92 142.24))
    (stroke (width 0) (type default))
  )
  (wire (pts (xy 275.59 66.04) (xy 278.13 66.04))
    (stroke (width 0) (type default))
  )
  (wire (pts (xy 80.01 147.32) (xy 91.44 147.32))
    (stroke (width 0) (type default))
  )
  (wire (pts (xy 224.282 162.56) (xy 247.65 162.56))
    (stroke (width 0) (type default))
  )
  (wire (pts (xy 317.5 139.7) (xy 344.17 139.7))
    (stroke (width 0) (type default))
  )
  (wire (pts (xy 404.114 129.54) (xy 372.11 129.54))
    (stroke (width 0) (type default))
  )
  (bus (pts (xy 127 116.84) (xy 127 119.38))
    (stroke (width 0) (type default))
  )

  (wire (pts (xy 245.11 93.98) (xy 247.65 93.98))
    (stroke (width 0) (type default))
  )
  (wire (pts (xy 317.5 154.94) (xy 344.17 154.94))
    (stroke (width 0) (type default))
  )
  (wire (pts (xy 80.01 35.56) (xy 94.488 35.56))
    (stroke (width 0) (type default))
  )
  (wire (pts (xy 375.92 81.28) (xy 375.92 88.9))
    (stroke (width 0) (type default))
  )
  (wire (pts (xy 50.165 147.32) (xy 50.165 149.86))
    (stroke (width 0) (type default))
  )
  (wire (pts (xy 372.11 157.48) (xy 404.114 157.48))
    (stroke (width 0) (type default))
  )
  (wire (pts (xy 52.07 50.8) (xy 50.165 50.8))
    (stroke (width 0) (type default))
  )
  (wire (pts (xy 245.11 71.12) (xy 245.11 78.74))
    (stroke (width 0) (type default))
  )
  (wire (pts (xy 247.65 33.02) (xy 224.282 33.02))
    (stroke (width 0) (type default))
  )
  (wire (pts (xy 80.01 60.96) (xy 81.915 60.96))
    (stroke (width 0) (type default))
  )
  (wire (pts (xy 404.114 139.7) (xy 372.11 139.7))
    (stroke (width 0) (type default))
  )
  (wire (pts (xy 81.28 230.505) (xy 88.265 230.505))
    (stroke (width 0) (type default))
  )
  (wire (pts (xy 176.53 78.74) (xy 194.31 78.74))
    (stroke (width 0) (type default))
  )
  (wire (pts (xy 176.53 160.02) (xy 187.96 160.02))
    (stroke (width 0) (type default))
  )
  (wire (pts (xy 134.62 196.85) (xy 134.62 200.66))
    (stroke (width 0) (type default))
  )
  (wire (pts (xy 148.59 48.26) (xy 136.525 48.26))
    (stroke (width 0) (type default))
  )
  (wire (pts (xy 224.282 154.94) (xy 247.65 154.94))
    (stroke (width 0) (type default))
  )
  (bus (pts (xy 125.73 124.46) (xy 127 124.46))
    (stroke (width 0) (type default))
  )

  (wire (pts (xy 340.36 71.12) (xy 340.36 78.74))
    (stroke (width 0) (type default))
  )
  (wire (pts (xy 52.07 83.82) (xy 40.64 83.82))
    (stroke (width 0) (type default))
  )
  (wire (pts (xy 404.114 124.46) (xy 372.11 124.46))
    (stroke (width 0) (type default))
  )
  (wire (pts (xy 372.11 33.02) (xy 375.92 33.02))
    (stroke (width 0) (type default))
  )
  (wire (pts (xy 80.01 30.48) (xy 81.915 30.48))
    (stroke (width 0) (type default))
  )
  (bus (pts (xy 31.75 116.84) (xy 31.75 119.38))
    (stroke (width 0) (type default))
  )

  (wire (pts (xy 176.53 99.06) (xy 194.31 99.06))
    (stroke (width 0) (type default))
  )
  (wire (pts (xy 80.01 144.78) (xy 81.915 144.78))
    (stroke (width 0) (type default))
  )
  (wire (pts (xy 304.8 196.85) (xy 304.8 198.12))
    (stroke (width 0) (type default))
  )
  (wire (pts (xy 258.445 267.97) (xy 258.445 265.43))
    (stroke (width 0) (type default))
  )
  (wire (pts (xy 85.09 55.88) (xy 95.885 55.88))
    (stroke (width 0) (type default))
  )
  (wire (pts (xy 146.05 157.48) (xy 146.05 160.02))
    (stroke (width 0) (type default))
  )
  (wire (pts (xy 404.114 78.74) (xy 372.11 78.74))
    (stroke (width 0) (type default))
  )
  (wire (pts (xy 99.695 206.375) (xy 104.775 206.375))
    (stroke (width 0) (type default))
  )
  (wire (pts (xy 245.11 167.64) (xy 247.65 167.64))
    (stroke (width 0) (type default))
  )
  (bus (pts (xy 100.33 119.38) (xy 101.6 119.38))
    (stroke (width 0) (type default))
  )

  (wire (pts (xy 302.26 175.26) (xy 275.59 175.26))
    (stroke (width 0) (type default))
  )
  (wire (pts (xy 375.92 66.04) (xy 375.92 73.66))
    (stroke (width 0) (type default))
  )
  (wire (pts (xy 176.53 96.52) (xy 194.31 96.52))
    (stroke (width 0) (type default))
  )
  (wire (pts (xy 245.11 48.26) (xy 245.11 55.88))
    (stroke (width 0) (type default))
  )
  (wire (pts (xy 302.26 165.1) (xy 275.59 165.1))
    (stroke (width 0) (type default))
  )
  (wire (pts (xy 247.65 111.76) (xy 224.282 111.76))
    (stroke (width 0) (type default))
  )
  (wire (pts (xy 146.05 50.8) (xy 146.05 58.42))
    (stroke (width 0) (type default))
  )
  (wire (pts (xy 404.114 137.16) (xy 372.11 137.16))
    (stroke (width 0) (type default))
  )
  (wire (pts (xy 314.96 198.12) (xy 314.96 196.85))
    (stroke (width 0) (type default))
  )
  (wire (pts (xy 81.915 30.48) (xy 81.915 38.1))
    (stroke (width 0) (type default))
  )
  (wire (pts (xy 45.72 175.26) (xy 52.07 175.26))
    (stroke (width 0) (type default))
  )
  (wire (pts (xy 317.5 83.82) (xy 344.17 83.82))
    (stroke (width 0) (type default))
  )
  (wire (pts (xy 80.01 33.02) (xy 94.488 33.02))
    (stroke (width 0) (type default))
  )
  (wire (pts (xy 404.114 106.68) (xy 372.11 106.68))
    (stroke (width 0) (type default))
  )
  (wire (pts (xy 375.92 73.66) (xy 375.92 81.28))
    (stroke (width 0) (type default))
  )
  (wire (pts (xy 356.235 210.82) (xy 386.08 210.82))
    (stroke (width 0) (type default))
  )
  (wire (pts (xy 99.695 196.85) (xy 100.965 196.85))
    (stroke (width 0) (type default))
  )
  (wire (pts (xy 146.05 76.2) (xy 146.05 86.36))
    (stroke (width 0) (type default))
  )
  (wire (pts (xy 81.915 45.72) (xy 81.915 53.34))
    (stroke (width 0) (type default))
  )
  (bus (pts (xy 127 95.25) (xy 125.73 95.25))
    (stroke (width 0) (type default))
  )

  (wire (pts (xy 340.36 27.94) (xy 340.36 35.56))
    (stroke (width 0) (type default))
  )
  (wire (pts (xy 180.34 165.1) (xy 176.53 165.1))
    (stroke (width 0) (type default))
  )
  (wire (pts (xy 245.745 267.97) (xy 247.015 267.97))
    (stroke (width 0) (type default))
  )
  (wire (pts (xy 247.65 196.85) (xy 257.81 196.85))
    (stroke (width 0) (type default))
  )
  (wire (pts (xy 80.01 162.56) (xy 81.915 162.56))
    (stroke (width 0) (type default))
  )
  (wire (pts (xy 278.13 40.64) (xy 275.59 40.64))
    (stroke (width 0) (type default))
  )
  (wire (pts (xy 245.11 157.48) (xy 245.11 167.64))
    (stroke (width 0) (type default))
  )
  (wire (pts (xy 80.01 45.72) (xy 81.915 45.72))
    (stroke (width 0) (type default))
  )
  (wire (pts (xy 245.11 48.26) (xy 247.65 48.26))
    (stroke (width 0) (type default))
  )
  (wire (pts (xy 245.745 265.43) (xy 245.745 267.97))
    (stroke (width 0) (type default))
  )
  (wire (pts (xy 186.055 260.985) (xy 184.785 260.985))
    (stroke (width 0) (type default))
  )
  (wire (pts (xy 32.385 212.725) (xy 41.275 212.725))
    (stroke (width 0) (type default))
  )
  (wire (pts (xy 80.01 160.02) (xy 91.44 160.02))
    (stroke (width 0) (type default))
  )
  (wire (pts (xy 80.01 170.18) (xy 91.44 170.18))
    (stroke (width 0) (type default))
  )
  (wire (pts (xy 245.11 147.32) (xy 247.65 147.32))
    (stroke (width 0) (type default))
  )
  (wire (pts (xy 148.59 157.48) (xy 146.05 157.48))
    (stroke (width 0) (type default))
  )
  (wire (pts (xy 372.11 127) (xy 375.92 127))
    (stroke (width 0) (type default))
  )
  (wire (pts (xy 317.5 88.9) (xy 344.17 88.9))
    (stroke (width 0) (type default))
  )
  (wire (pts (xy 247.65 106.68) (xy 224.282 106.68))
    (stroke (width 0) (type default))
  )
  (wire (pts (xy 245.11 124.46) (xy 245.11 132.08))
    (stroke (width 0) (type default))
  )
  (wire (pts (xy 52.07 154.94) (xy 40.64 154.94))
    (stroke (width 0) (type default))
  )
  (wire (pts (xy 80.01 43.18) (xy 94.488 43.18))
    (stroke (width 0) (type default))
  )
  (wire (pts (xy 176.53 35.56) (xy 187.96 35.56))
    (stroke (width 0) (type default))
  )
  (wire (pts (xy 88.265 215.9) (xy 96.52 215.9))
    (stroke (width 0) (type default))
  )
  (wire (pts (xy 245.11 137.16) (xy 247.65 137.16))
    (stroke (width 0) (type default))
  )
  (wire (pts (xy 275.59 43.18) (xy 278.13 43.18))
    (stroke (width 0) (type default))
  )
  (wire (pts (xy 80.01 86.36) (xy 110.49 86.36))
    (stroke (width 0) (type default))
  )
  (wire (pts (xy 169.545 213.36) (xy 165.1 213.36))
    (stroke (width 0) (type default))
  )
  (wire (pts (xy 302.26 139.7) (xy 275.59 139.7))
    (stroke (width 0) (type default))
  )
  (wire (pts (xy 148.59 27.94) (xy 146.05 27.94))
    (stroke (width 0) (type default))
  )
  (wire (pts (xy 340.36 78.74) (xy 340.36 86.36))
    (stroke (width 0) (type default))
  )
  (wire (pts (xy 302.26 109.22) (xy 275.59 109.22))
    (stroke (width 0) (type default))
  )
  (wire (pts (xy 302.26 147.32) (xy 275.59 147.32))
    (stroke (width 0) (type default))
  )
  (wire (pts (xy 245.11 27.94) (xy 245.11 35.56))
    (stroke (width 0) (type default))
  )
  (wire (pts (xy 81.915 165.1) (xy 81.915 172.72))
    (stroke (width 0) (type default))
  )
  (wire (pts (xy 372.11 142.24) (xy 375.92 142.24))
    (stroke (width 0) (type default))
  )
  (wire (pts (xy 340.36 25.4) (xy 344.17 25.4))
    (stroke (width 0) (type default))
  )
  (wire (pts (xy 404.114 27.94) (xy 372.11 27.94))
    (stroke (width 0) (type default))
  )
  (wire (pts (xy 19.685 25.4) (xy 52.07 25.4))
    (stroke (width 0) (type default))
  )
  (wire (pts (xy 302.26 27.94) (xy 275.59 27.94))
    (stroke (width 0) (type default))
  )
  (wire (pts (xy 314.96 223.52) (xy 314.96 222.25))
    (stroke (width 0) (type default))
  )
  (wire (pts (xy 148.59 33.02) (xy 134.874 33.02))
    (stroke (width 0) (type default))
  )
  (wire (pts (xy 247.65 222.25) (xy 257.81 222.25))
    (stroke (width 0) (type default))
  )
  (wire (pts (xy 278.13 119.38) (xy 278.13 127))
    (stroke (width 0) (type default))
  )
  (wire (pts (xy 80.01 152.4) (xy 81.915 152.4))
    (stroke (width 0) (type default))
  )
  (wire (pts (xy 302.26 93.98) (xy 275.59 93.98))
    (stroke (width 0) (type default))
  )
  (wire (pts (xy 80.01 55.88) (xy 85.09 55.88))
    (stroke (width 0) (type default))
  )
  (wire (pts (xy 180.34 25.4) (xy 180.34 27.94))
    (stroke (width 0) (type default))
  )
  (wire (pts (xy 180.34 152.4) (xy 176.53 152.4))
    (stroke (width 0) (type default))
  )
  (wire (pts (xy 52.07 63.5) (xy 34.29 63.5))
    (stroke (width 0) (type default))
  )
  (wire (pts (xy 50.165 88.9) (xy 52.07 88.9))
    (stroke (width 0) (type default))
  )
  (wire (pts (xy 275.59 111.76) (xy 278.13 111.76))
    (stroke (width 0) (type default))
  )
  (bus (pts (xy 196.85 132.08) (xy 196.85 134.62))
    (stroke (width 0) (type default))
  )

  (wire (pts (xy 247.65 88.9) (xy 224.282 88.9))
    (stroke (width 0) (type default))
  )
  (wire (pts (xy 81.915 144.78) (xy 81.915 152.4))
    (stroke (width 0) (type default))
  )
  (wire (pts (xy 34.29 132.08) (xy 52.07 132.08))
    (stroke (width 0) (type default))
  )
  (wire (pts (xy 317.5 144.78) (xy 344.17 144.78))
    (stroke (width 0) (type default))
  )
  (wire (pts (xy 326.39 198.12) (xy 326.39 196.85))
    (stroke (width 0) (type default))
  )
  (wire (pts (xy 88.265 196.85) (xy 88.265 199.39))
    (stroke (width 0) (type default))
  )
  (wire (pts (xy 52.07 165.1) (xy 25.4 165.1))
    (stroke (width 0) (type default))
  )
  (wire (pts (xy 116.205 213.36) (xy 127.635 213.36))
    (stroke (width 0) (type default))
  )
  (wire (pts (xy 404.114 93.98) (xy 372.11 93.98))
    (stroke (width 0) (type default))
  )
  (wire (pts (xy 148.59 30.48) (xy 134.874 30.48))
    (stroke (width 0) (type default))
  )
  (wire (pts (xy 275.59 104.14) (xy 278.13 104.14))
    (stroke (width 0) (type default))
  )
  (wire (pts (xy 148.59 73.66) (xy 130.81 73.66))
    (stroke (width 0) (type default))
  )
  (wire (pts (xy 224.282 160.02) (xy 247.65 160.02))
    (stroke (width 0) (type default))
  )
  (wire (pts (xy 148.59 93.98) (xy 121.666 93.98))
    (stroke (width 0) (type default))
  )
  (wire (pts (xy 302.26 45.72) (xy 275.59 45.72))
    (stroke (width 0) (type default))
  )
  (wire (pts (xy 340.36 109.22) (xy 344.17 109.22))
    (stroke (width 0) (type default))
  )
  (bus (pts (xy 100.33 129.54) (xy 100.33 132.08))
    (stroke (width 0) (type default))
  )

  (wire (pts (xy 176.53 157.48) (xy 187.96 157.48))
    (stroke (width 0) (type default))
  )
  (wire (pts (xy 372.11 66.04) (xy 375.92 66.04))
    (stroke (width 0) (type default))
  )
  (wire (pts (xy 317.5 66.04) (xy 344.17 66.04))
    (stroke (width 0) (type default))
  )
  (wire (pts (xy 176.53 106.68) (xy 194.31 106.68))
    (stroke (width 0) (type default))
  )
  (wire (pts (xy 302.26 160.02) (xy 275.59 160.02))
    (stroke (width 0) (type default))
  )
  (wire (pts (xy 176.53 127) (xy 194.31 127))
    (stroke (width 0) (type default))
  )
  (wire (pts (xy 81.915 121.92) (xy 80.01 121.92))
    (stroke (width 0) (type default))
  )
  (wire (pts (xy 80.01 172.72) (xy 81.915 172.72))
    (stroke (width 0) (type default))
  )
  (wire (pts (xy 180.34 154.94) (xy 176.53 154.94))
    (stroke (width 0) (type default))
  )
  (wire (pts (xy 404.114 25.4) (xy 372.11 25.4))
    (stroke (width 0) (type default))
  )
  (wire (pts (xy 25.4 99.06) (xy 52.07 99.06))
    (stroke (width 0) (type default))
  )
  (wire (pts (xy 317.5 129.54) (xy 344.17 129.54))
    (stroke (width 0) (type default))
  )
  (wire (pts (xy 155.575 205.74) (xy 155.575 213.36))
    (stroke (width 0) (type default))
  )
  (wire (pts (xy 148.59 91.44) (xy 137.16 91.44))
    (stroke (width 0) (type default))
  )
  (wire (pts (xy 302.26 68.58) (xy 275.59 68.58))
    (stroke (width 0) (type default))
  )
  (wire (pts (xy 375.92 43.18) (xy 375.92 50.8))
    (stroke (width 0) (type default))
  )
  (wire (pts (xy 340.36 38.1) (xy 344.17 38.1))
    (stroke (width 0) (type default))
  )
  (polyline (pts (xy 224.79 246.38) (xy 344.805 246.38))
    (stroke (width 0) (type default))
  )

  (wire (pts (xy 302.26 172.72) (xy 275.59 172.72))
    (stroke (width 0) (type default))
  )
  (wire (pts (xy 317.5 104.14) (xy 344.17 104.14))
    (stroke (width 0) (type default))
  )
  (wire (pts (xy 372.11 119.38) (xy 375.92 119.38))
    (stroke (width 0) (type default))
  )
  (wire (pts (xy 80.01 53.34) (xy 81.915 53.34))
    (stroke (width 0) (type default))
  )
  (wire (pts (xy 176.53 119.38) (xy 194.31 119.38))
    (stroke (width 0) (type default))
  )
  (wire (pts (xy 258.445 265.43) (xy 262.255 265.43))
    (stroke (width 0) (type default))
  )
  (bus (pts (xy 100.33 132.08) (xy 100.33 134.62))
    (stroke (width 0) (type default))
  )

  (wire (pts (xy 326.39 223.52) (xy 326.39 222.25))
    (stroke (width 0) (type default))
  )
  (wire (pts (xy 404.114 60.96) (xy 372.11 60.96))
    (stroke (width 0) (type default))
  )
  (wire (pts (xy 247.65 35.56) (xy 245.11 35.56))
    (stroke (width 0) (type default))
  )
  (wire (pts (xy 278.13 30.48) (xy 278.13 33.02))
    (stroke (width 0) (type default))
  )
  (wire (pts (xy 104.775 206.375) (xy 104.775 210.82))
    (stroke (width 0) (type default))
  )
  (wire (pts (xy 302.26 25.4) (xy 275.59 25.4))
    (stroke (width 0) (type default))
  )
  (wire (pts (xy 317.5 43.18) (xy 344.17 43.18))
    (stroke (width 0) (type default))
  )
  (wire (pts (xy 404.114 48.26) (xy 372.11 48.26))
    (stroke (width 0) (type default))
  )
  (wire (pts (xy 50.165 50.8) (xy 50.165 58.42))
    (stroke (width 0) (type default))
  )
  (wire (pts (xy 372.11 170.18) (xy 404.114 170.18))
    (stroke (width 0) (type default))
  )
  (bus (pts (xy 196.85 104.14) (xy 196.85 106.68))
    (stroke (width 0) (type default))
  )

  (wire (pts (xy 144.145 175.26) (xy 148.59 175.26))
    (stroke (width 0) (type default))
  )
  (wire (pts (xy 81.915 176.53) (xy 81.915 172.72))
    (stroke (width 0) (type default))
  )
  (wire (pts (xy 176.53 162.56) (xy 180.34 162.56))
    (stroke (width 0) (type default))
  )
  (wire (pts (xy 262.255 265.43) (xy 283.845 265.43))
    (stroke (width 0) (type default))
  )
  (wire (pts (xy 302.26 38.1) (xy 275.59 38.1))
    (stroke (width 0) (type default))
  )
  (wire (pts (xy 302.26 101.6) (xy 275.59 101.6))
    (stroke (width 0) (type default))
  )
  (wire (pts (xy 50.165 139.7) (xy 50.165 147.32))
    (stroke (width 0) (type default))
  )
  (wire (pts (xy 80.01 109.22) (xy 98.552 109.22))
    (stroke (width 0) (type default))
  )
  (wire (pts (xy 257.81 196.85) (xy 267.97 196.85))
    (stroke (width 0) (type default))
  )
  (bus (pts (xy 100.33 111.76) (xy 100.33 114.3))
    (stroke (width 0) (type default))
  )

  (wire (pts (xy 372.11 172.72) (xy 404.495 172.72))
    (stroke (width 0) (type default))
  )
  (wire (pts (xy 245.11 132.08) (xy 245.11 137.16))
    (stroke (width 0) (type default))
  )
  (wire (pts (xy 80.01 66.04) (xy 96.774 66.04))
    (stroke (width 0) (type default))
  )
  (wire (pts (xy 176.53 68.58) (xy 187.96 68.58))
    (stroke (width 0) (type default))
  )
  (wire (pts (xy 278.13 96.52) (xy 275.59 96.52))
    (stroke (width 0) (type default))
  )
  (wire (pts (xy 146.05 116.84) (xy 148.59 116.84))
    (stroke (width 0) (type default))
  )
  (wire (pts (xy 34.29 121.92) (xy 52.07 121.92))
    (stroke (width 0) (type default))
  )
  (wire (pts (xy 81.915 132.08) (xy 81.915 142.24))
    (stroke (width 0) (type default))
  )
  (wire (pts (xy 176.53 104.14) (xy 186.69 104.14))
    (stroke (width 0) (type default))
  )
  (wire (pts (xy 45.72 172.72) (xy 45.72 175.26))
    (stroke (width 0) (type default))
  )
  (wire (pts (xy 81.915 38.1) (xy 81.915 45.72))
    (stroke (width 0) (type default))
  )
  (wire (pts (xy 247.65 83.82) (xy 224.282 83.82))
    (stroke (width 0) (type default))
  )
  (wire (pts (xy 304.8 196.85) (xy 302.26 196.85))
    (stroke (width 0) (type default))
  )
  (wire (pts (xy 80.01 88.9) (xy 110.49 88.9))
    (stroke (width 0) (type default))
  )
  (wire (pts (xy 34.29 134.62) (xy 52.07 134.62))
    (stroke (width 0) (type default))
  )
  (wire (pts (xy 317.5 40.64) (xy 344.17 40.64))
    (stroke (width 0) (type default))
  )
  (wire (pts (xy 148.59 172.72) (xy 144.145 172.72))
    (stroke (width 0) (type default))
  )
  (wire (pts (xy 50.165 127) (xy 50.165 137.16))
    (stroke (width 0) (type default))
  )
  (wire (pts (xy 144.145 175.26) (xy 144.145 172.72))
    (stroke (width 0) (type default))
  )
  (polyline (pts (xy 344.805 246.38) (xy 344.805 252.73))
    (stroke (width 0) (type default))
  )

  (bus (pts (xy 128.27 74.93) (xy 127 74.93))
    (stroke (width 0) (type default))
  )
  (bus (pts (xy 100.33 124.46) (xy 100.33 127))
    (stroke (width 0) (type default))
  )

  (wire (pts (xy 32.385 208.28) (xy 32.385 212.725))
    (stroke (width 0) (type default))
  )
  (wire (pts (xy 52.07 167.64) (xy 50.165 167.64))
    (stroke (width 0) (type default))
  )
  (wire (pts (xy 176.53 81.28) (xy 180.34 81.28))
    (stroke (width 0) (type default))
  )
  (wire (pts (xy 52.07 81.28) (xy 40.64 81.28))
    (stroke (width 0) (type default))
  )
  (wire (pts (xy 25.4 96.52) (xy 52.07 96.52))
    (stroke (width 0) (type default))
  )
  (wire (pts (xy 245.11 35.56) (xy 245.11 38.1))
    (stroke (width 0) (type default))
  )
  (bus (pts (xy 100.33 129.54) (xy 101.6 129.54))
    (stroke (width 0) (type default))
  )

  (wire (pts (xy 134.62 196.85) (xy 141.605 196.85))
    (stroke (width 0) (type default))
  )
  (wire (pts (xy 155.575 213.36) (xy 160.02 213.36))
    (stroke (width 0) (type default))
  )
  (wire (pts (xy 50.165 27.94) (xy 50.165 35.56))
    (stroke (width 0) (type default))
  )
  (wire (pts (xy 404.114 35.56) (xy 372.11 35.56))
    (stroke (width 0) (type default))
  )
  (wire (pts (xy 247.65 114.3) (xy 224.282 114.3))
    (stroke (width 0) (type default))
  )
  (wire (pts (xy 257.81 222.25) (xy 267.97 222.25))
    (stroke (width 0) (type default))
  )
  (wire (pts (xy 88.265 224.155) (xy 88.265 230.505))
    (stroke (width 0) (type default))
  )
  (wire (pts (xy 146.05 58.42) (xy 146.05 66.04))
    (stroke (width 0) (type default))
  )
  (wire (pts (xy 50.165 76.2) (xy 52.07 76.2))
    (stroke (width 0) (type default))
  )
  (wire (pts (xy 52.07 91.44) (xy 25.4 91.44))
    (stroke (width 0) (type default))
  )
  (wire (pts (xy 245.11 78.74) (xy 247.65 78.74))
    (stroke (width 0) (type default))
  )
  (wire (pts (xy 97.155 215.9) (xy 96.52 215.9))
    (stroke (width 0) (type default))
  )
  (wire (pts (xy 176.53 149.86) (xy 187.96 149.86))
    (stroke (width 0) (type default))
  )
  (wire (pts (xy 245.11 25.4) (xy 245.11 27.94))
    (stroke (width 0) (type default))
  )
  (wire (pts (xy 302.26 91.44) (xy 275.59 91.44))
    (stroke (width 0) (type default))
  )
  (wire (pts (xy 247.65 30.48) (xy 224.282 30.48))
    (stroke (width 0) (type default))
  )
  (wire (pts (xy 80.01 38.1) (xy 81.915 38.1))
    (stroke (width 0) (type default))
  )
  (wire (pts (xy 176.53 63.5) (xy 187.96 63.5))
    (stroke (width 0) (type default))
  )
  (wire (pts (xy 186.055 276.86) (xy 184.785 276.86))
    (stroke (width 0) (type default))
  )
  (wire (pts (xy 81.915 91.44) (xy 81.915 101.6))
    (stroke (width 0) (type default))
  )
  (wire (pts (xy 317.5 73.66) (xy 344.17 73.66))
    (stroke (width 0) (type default))
  )
  (wire (pts (xy 146.05 170.18) (xy 148.59 170.18))
    (stroke (width 0) (type default))
  )
  (wire (pts (xy 80.01 93.98) (xy 110.236 93.98))
    (stroke (width 0) (type default))
  )
  (bus (pts (xy 127 127) (xy 127 129.54))
    (stroke (width 0) (type default))
  )

  (wire (pts (xy 50.165 157.48) (xy 50.165 160.02))
    (stroke (width 0) (type default))
  )
  (wire (pts (xy 317.5 106.68) (xy 344.17 106.68))
    (stroke (width 0) (type default))
  )
  (wire (pts (xy 340.36 45.72) (xy 344.17 45.72))
    (stroke (width 0) (type default))
  )
  (wire (pts (xy 146.05 27.94) (xy 146.05 35.56))
    (stroke (width 0) (type default))
  )
  (wire (pts (xy 148.59 43.18) (xy 146.05 43.18))
    (stroke (width 0) (type default))
  )
  (wire (pts (xy 245.745 267.97) (xy 245.745 271.78))
    (stroke (width 0) (type default))
  )
  (wire (pts (xy 80.01 27.94) (xy 91.44 27.94))
    (stroke (width 0) (type default))
  )
  (wire (pts (xy 340.36 63.5) (xy 344.17 63.5))
    (stroke (width 0) (type default))
  )
  (wire (pts (xy 247.65 73.66) (xy 224.282 73.66))
    (stroke (width 0) (type default))
  )
  (wire (pts (xy 121.92 261.62) (xy 120.65 261.62))
    (stroke (width 0) (type default))
  )
  (wire (pts (xy 50.165 116.84) (xy 50.165 127))
    (stroke (width 0) (type default))
  )
  (wire (pts (xy 247.65 40.64) (xy 224.282 40.64))
    (stroke (width 0) (type default))
  )
  (wire (pts (xy 88.265 215.9) (xy 88.265 219.075))
    (stroke (width 0) (type default))
  )
  (wire (pts (xy 278.13 50.8) (xy 275.59 50.8))
    (stroke (width 0) (type default))
  )
  (bus (pts (xy 127 111.76) (xy 127 113.03))
    (stroke (width 0) (type default))
  )

  (wire (pts (xy 302.26 55.88) (xy 275.59 55.88))
    (stroke (width 0) (type default))
  )
  (wire (pts (xy 81.915 162.56) (xy 81.915 165.1))
    (stroke (width 0) (type default))
  )
  (wire (pts (xy 340.36 86.36) (xy 344.17 86.36))
    (stroke (width 0) (type default))
  )
  (wire (pts (xy 340.36 147.32) (xy 340.36 157.48))
    (stroke (width 0) (type default))
  )
  (wire (pts (xy 372.11 30.48) (xy 375.92 30.48))
    (stroke (width 0) (type default))
  )
  (bus (pts (xy 127 96.52) (xy 127 99.06))
    (stroke (width 0) (type default))
  )

  (wire (pts (xy 80.01 58.42) (xy 85.09 58.42))
    (stroke (width 0) (type default))
  )
  (wire (pts (xy 404.114 86.36) (xy 372.11 86.36))
    (stroke (width 0) (type default))
  )
  (wire (pts (xy 262.255 265.43) (xy 262.255 266.7))
    (stroke (width 0) (type default))
  )
  (wire (pts (xy 80.01 154.94) (xy 81.915 154.94))
    (stroke (width 0) (type default))
  )
  (wire (pts (xy 176.53 91.44) (xy 180.34 91.44))
    (stroke (width 0) (type default))
  )
  (wire (pts (xy 340.36 45.72) (xy 340.36 48.26))
    (stroke (width 0) (type default))
  )
  (wire (pts (xy 245.11 78.74) (xy 245.11 86.36))
    (stroke (width 0) (type default))
  )
  (wire (pts (xy 278.13 50.8) (xy 278.13 58.42))
    (stroke (width 0) (type default))
  )
  (wire (pts (xy 52.07 111.76) (xy 40.64 111.76))
    (stroke (width 0) (type default))
  )
  (wire (pts (xy 404.114 116.84) (xy 372.11 116.84))
    (stroke (width 0) (type default))
  )
  (wire (pts (xy 304.8 222.25) (xy 302.26 222.25))
    (stroke (width 0) (type default))
  )
  (wire (pts (xy 40.64 86.36) (xy 52.07 86.36))
    (stroke (width 0) (type default))
  )
  (wire (pts (xy 148.59 60.96) (xy 137.16 60.96))
    (stroke (width 0) (type default))
  )
  (wire (pts (xy 121.92 262.89) (xy 121.92 261.62))
    (stroke (width 0) (type default))
  )
  (bus (pts (xy 31.75 114.3) (xy 30.48 114.3))
    (stroke (width 0) (type default))
  )

  (wire (pts (xy 80.01 139.7) (xy 97.79 139.7))
    (stroke (width 0) (type default))
  )
  (wire (pts (xy 52.07 170.18) (xy 50.165 170.18))
    (stroke (width 0) (type default))
  )
  (bus (pts (xy 107.95 71.12) (xy 107.95 76.2))
    (stroke (width 0) (type default))
  )

  (wire (pts (xy 50.165 106.68) (xy 50.165 116.84))
    (stroke (width 0) (type default))
  )
  (wire (pts (xy 386.08 213.36) (xy 356.235 213.36))
    (stroke (width 0) (type default))
  )
  (wire (pts (xy 213.995 207.772) (xy 213.995 212.09))
    (stroke (width 0) (type default))
  )
  (wire (pts (xy 195.453 207.772) (xy 213.995 207.772))
    (stroke (width 0) (type default))
  )
  (wire (pts (xy 80.01 83.82) (xy 110.49 83.82))
    (stroke (width 0) (type default))
  )
  (wire (pts (xy 278.13 66.04) (xy 278.13 73.66))
    (stroke (width 0) (type default))
  )
  (wire (pts (xy 153.035 276.86) (xy 151.765 276.86))
    (stroke (width 0) (type default))
  )
  (wire (pts (xy 127.635 196.85) (xy 134.62 196.85))
    (stroke (width 0) (type default))
  )
  (wire (pts (xy 127.635 205.74) (xy 127.635 213.36))
    (stroke (width 0) (type default))
  )
  (wire (pts (xy 52.07 55.88) (xy 25.4 55.88))
    (stroke (width 0) (type default))
  )
  (wire (pts (xy 96.52 215.9) (xy 96.52 225.425))
    (stroke (width 0) (type default))
  )
  (wire (pts (xy 50.165 106.68) (xy 52.07 106.68))
    (stroke (width 0) (type default))
  )
  (wire (pts (xy 340.36 101.6) (xy 340.36 109.22))
    (stroke (width 0) (type default))
  )
  (wire (pts (xy 340.36 25.4) (xy 340.36 27.94))
    (stroke (width 0) (type default))
  )
  (wire (pts (xy 340.36 124.46) (xy 344.17 124.46))
    (stroke (width 0) (type default))
  )
  (wire (pts (xy 52.07 162.56) (xy 25.4 162.56))
    (stroke (width 0) (type default))
  )
  (wire (pts (xy 129.54 134.62) (xy 148.59 134.62))
    (stroke (width 0) (type default))
  )
  (wire (pts (xy 372.11 160.02) (xy 404.114 160.02))
    (stroke (width 0) (type default))
  )
  (wire (pts (xy 404.114 134.62) (xy 372.11 134.62))
    (stroke (width 0) (type default))
  )
  (wire (pts (xy 302.26 78.74) (xy 275.59 78.74))
    (stroke (width 0) (type default))
  )
  (wire (pts (xy 80.01 106.68) (xy 91.44 106.68))
    (stroke (width 0) (type default))
  )
  (wire (pts (xy 317.5 170.18) (xy 344.17 170.18))
    (stroke (width 0) (type default))
  )
  (wire (pts (xy 146.05 106.68) (xy 148.59 106.68))
    (stroke (width 0) (type default))
  )
  (wire (pts (xy 148.59 205.74) (xy 148.59 213.36))
    (stroke (width 0) (type default))
  )
  (wire (pts (xy 372.11 132.08) (xy 375.92 132.08))
    (stroke (width 0) (type default))
  )
  (wire (pts (xy 81.915 71.12) (xy 80.01 71.12))
    (stroke (width 0) (type default))
  )
  (wire (pts (xy 81.915 121.92) (xy 81.915 132.08))
    (stroke (width 0) (type default))
  )
  (wire (pts (xy 340.36 27.94) (xy 344.17 27.94))
    (stroke (width 0) (type default))
  )
  (wire (pts (xy 176.53 40.64) (xy 187.96 40.64))
    (stroke (width 0) (type default))
  )
  (wire (pts (xy 41.275 208.28) (xy 41.275 212.725))
    (stroke (width 0) (type default))
  )
  (wire (pts (xy 148.59 196.85) (xy 148.59 200.66))
    (stroke (width 0) (type default))
  )
  (wire (pts (xy 302.26 157.48) (xy 275.59 157.48))
    (stroke (width 0) (type default))
  )
  (wire (pts (xy 52.07 30.48) (xy 40.64 30.48))
    (stroke (width 0) (type default))
  )
  (wire (pts (xy 52.07 157.48) (xy 50.165 157.48))
    (stroke (width 0) (type default))
  )
  (wire (pts (xy 176.53 48.26) (xy 187.96 48.26))
    (stroke (width 0) (type default))
  )
  (wire (pts (xy 356.235 203.2) (xy 386.08 203.2))
    (stroke (width 0) (type default))
  )
  (wire (pts (xy 278.13 73.66) (xy 278.13 81.28))
    (stroke (width 0) (type default))
  )
  (wire (pts (xy 116.205 196.85) (xy 116.205 199.39))
    (stroke (width 0) (type default))
  )
  (wire (pts (xy 245.11 222.25) (xy 247.65 222.25))
    (stroke (width 0) (type default))
  )
  (wire (pts (xy 245.11 55.88) (xy 247.65 55.88))
    (stroke (width 0) (type default))
  )
  (wire (pts (xy 356.235 200.66) (xy 386.08 200.66))
    (stroke (width 0) (type default))
  )
  (wire (pts (xy 247.65 27.94) (xy 245.11 27.94))
    (stroke (width 0) (type default))
  )
  (bus (pts (xy 196.85 119.38) (xy 196.85 121.92))
    (stroke (width 0) (type default))
  )

  (wire (pts (xy 134.62 205.74) (xy 134.62 213.36))
    (stroke (width 0) (type default))
  )
  (wire (pts (xy 275.59 81.28) (xy 278.13 81.28))
    (stroke (width 0) (type default))
  )
  (wire (pts (xy 257.175 267.97) (xy 258.445 267.97))
    (stroke (width 0) (type default))
  )
  (wire (pts (xy 224.282 134.62) (xy 247.65 134.62))
    (stroke (width 0) (type default))
  )
  (wire (pts (xy 375.92 96.52) (xy 375.92 104.14))
    (stroke (width 0) (type default))
  )
  (wire (pts (xy 81.915 81.28) (xy 81.915 91.44))
    (stroke (width 0) (type default))
  )
  (wire (pts (xy 304.8 222.25) (xy 304.8 223.52))
    (stroke (width 0) (type default))
  )
  (wire (pts (xy 176.53 132.08) (xy 180.34 132.08))
    (stroke (width 0) (type default))
  )
  (wire (pts (xy 176.53 109.22) (xy 194.31 109.22))
    (stroke (width 0) (type default))
  )
  (wire (pts (xy 340.36 116.84) (xy 340.36 124.46))
    (stroke (width 0) (type default))
  )
  (wire (pts (xy 52.07 127) (xy 50.165 127))
    (stroke (width 0) (type default))
  )
  (wire (pts (xy 257.81 198.12) (xy 257.81 196.85))
    (stroke (width 0) (type default))
  )
  (wire (pts (xy 176.53 76.2) (xy 194.31 76.2))
    (stroke (width 0) (type default))
  )
  (wire (pts (xy 148.59 149.86) (xy 146.05 149.86))
    (stroke (width 0) (type default))
  )
  (wire (pts (xy 146.05 66.04) (xy 146.05 76.2))
    (stroke (width 0) (type default))
  )
  (wire (pts (xy 180.34 45.72) (xy 176.53 45.72))
    (stroke (width 0) (type default))
  )
  (bus (pts (xy 199.39 119.38) (xy 196.85 119.38))
    (stroke (width 0) (type default))
  )

  (wire (pts (xy 80.01 134.62) (xy 97.79 134.62))
    (stroke (width 0) (type default))
  )
  (wire (pts (xy 121.92 269.875) (xy 120.65 269.875))
    (stroke (width 0) (type default))
  )
  (wire (pts (xy 302.26 124.46) (xy 275.59 124.46))
    (stroke (width 0) (type default))
  )
  (wire (pts (xy 356.235 208.28) (xy 386.08 208.28))
    (stroke (width 0) (type default))
  )
  (bus (pts (xy 127 119.38) (xy 127 121.92))
    (stroke (width 0) (type default))
  )

  (wire (pts (xy 317.5 134.62) (xy 344.17 134.62))
    (stroke (width 0) (type default))
  )
  (wire (pts (xy 375.92 119.38) (xy 375.92 127))
    (stroke (width 0) (type default))
  )
  (wire (pts (xy 247.015 265.43) (xy 245.745 265.43))
    (stroke (width 0) (type default))
  )
  (wire (pts (xy 247.65 81.28) (xy 224.282 81.28))
    (stroke (width 0) (type default))
  )
  (wire (pts (xy 141.605 196.85) (xy 141.605 200.66))
    (stroke (width 0) (type default))
  )
  (wire (pts (xy 302.26 35.56) (xy 275.59 35.56))
    (stroke (width 0) (type default))
  )
  (wire (pts (xy 33.02 66.04) (xy 52.07 66.04))
    (stroke (width 0) (type default))
  )
  (wire (pts (xy 356.235 215.9) (xy 386.08 215.9))
    (stroke (width 0) (type default))
  )
  (wire (pts (xy 146.05 76.2) (xy 148.59 76.2))
    (stroke (width 0) (type default))
  )
  (wire (pts (xy 245.11 101.6) (xy 247.65 101.6))
    (stroke (width 0) (type default))
  )
  (wire (pts (xy 317.5 76.2) (xy 344.17 76.2))
    (stroke (width 0) (type default))
  )
  (wire (pts (xy 275.59 119.38) (xy 278.13 119.38))
    (stroke (width 0) (type default))
  )
  (wire (pts (xy 52.07 116.84) (xy 50.165 116.84))
    (stroke (width 0) (type default))
  )
  (wire (pts (xy 121.92 253.365) (xy 121.92 255.905))
    (stroke (width 0) (type default))
  )
  (wire (pts (xy 50.165 167.64) (xy 50.165 170.18))
    (stroke (width 0) (type default))
  )
  (wire (pts (xy 344.17 157.48) (xy 340.36 157.48))
    (stroke (width 0) (type default))
  )
  (wire (pts (xy 340.36 167.64) (xy 340.36 176.53))
    (stroke (width 0) (type default))
  )
  (wire (pts (xy 180.34 25.4) (xy 191.135 25.4))
    (stroke (width 0) (type default))
  )
  (wire (pts (xy 340.36 35.56) (xy 340.36 38.1))
    (stroke (width 0) (type default))
  )
  (bus (pts (xy 196.85 109.22) (xy 198.12 109.22))
    (stroke (width 0) (type default))
  )
  (bus (pts (xy 127 129.54) (xy 127 132.08))
    (stroke (width 0) (type default))
  )

  (wire (pts (xy 176.53 144.78) (xy 180.34 144.78))
    (stroke (width 0) (type default))
  )
  (wire (pts (xy 169.545 205.74) (xy 169.545 213.36))
    (stroke (width 0) (type default))
  )
  (wire (pts (xy 146.05 127) (xy 148.59 127))
    (stroke (width 0) (type default))
  )
  (wire (pts (xy 81.915 142.24) (xy 80.01 142.24))
    (stroke (width 0) (type default))
  )
  (wire (pts (xy 375.92 88.9) (xy 375.92 96.52))
    (stroke (width 0) (type default))
  )
  (wire (pts (xy 247.65 53.34) (xy 224.282 53.34))
    (stroke (width 0) (type default))
  )
  (wire (pts (xy 302.26 149.86) (xy 275.59 149.86))
    (stroke (width 0) (type default))
  )
  (wire (pts (xy 245.11 157.48) (xy 247.65 157.48))
    (stroke (width 0) (type default))
  )
  (wire (pts (xy 80.01 129.54) (xy 97.79 129.54))
    (stroke (width 0) (type default))
  )
  (wire (pts (xy 278.13 196.85) (xy 278.13 198.12))
    (stroke (width 0) (type default))
  )
  (wire (pts (xy 245.11 45.72) (xy 245.11 48.26))
    (stroke (width 0) (type default))
  )
  (wire (pts (xy 52.07 147.32) (xy 50.165 147.32))
    (stroke (width 0) (type default))
  )
  (wire (pts (xy 340.36 63.5) (xy 340.36 71.12))
    (stroke (width 0) (type default))
  )
  (wire (pts (xy 80.01 114.3) (xy 97.79 114.3))
    (stroke (width 0) (type default))
  )
  (wire (pts (xy 180.34 38.1) (xy 176.53 38.1))
    (stroke (width 0) (type default))
  )
  (wire (pts (xy 176.53 111.76) (xy 180.34 111.76))
    (stroke (width 0) (type default))
  )
  (wire (pts (xy 326.39 222.25) (xy 314.96 222.25))
    (stroke (width 0) (type default))
  )
  (wire (pts (xy 302.26 76.2) (xy 275.59 76.2))
    (stroke (width 0) (type default))
  )
  (wire (pts (xy 340.36 157.48) (xy 340.36 167.64))
    (stroke (width 0) (type default))
  )
  (wire (pts (xy 317.5 160.02) (xy 344.17 160.02))
    (stroke (width 0) (type default))
  )
  (bus (pts (xy 127 114.3) (xy 127 116.84))
    (stroke (width 0) (type default))
  )
  (bus (pts (xy 101.6 110.49) (xy 100.33 110.49))
    (stroke (width 0) (type default))
  )

  (wire (pts (xy 275.59 132.08) (xy 278.13 132.08))
    (stroke (width 0) (type default))
  )
  (wire (pts (xy 267.97 196.85) (xy 267.97 198.12))
    (stroke (width 0) (type default))
  )
  (wire (pts (xy 372.11 111.76) (xy 375.92 111.76))
    (stroke (width 0) (type default))
  )
  (wire (pts (xy 375.92 50.8) (xy 375.92 58.42))
    (stroke (width 0) (type default))
  )
  (wire (pts (xy 146.05 149.86) (xy 146.05 157.48))
    (stroke (width 0) (type default))
  )
  (wire (pts (xy 80.01 40.64) (xy 94.488 40.64))
    (stroke (width 0) (type default))
  )
  (wire (pts (xy 404.114 114.3) (xy 372.11 114.3))
    (stroke (width 0) (type default))
  )
  (wire (pts (xy 50.165 160.02) (xy 50.165 167.64))
    (stroke (width 0) (type default))
  )
  (wire (pts (xy 148.59 63.5) (xy 137.16 63.5))
    (stroke (width 0) (type default))
  )
  (wire (pts (xy 59.055 214.63) (xy 59.055 212.725))
    (stroke (width 0) (type default))
  )
  (wire (pts (xy 278.13 127) (xy 278.13 132.08))
    (stroke (width 0) (type default))
  )
  (wire (pts (xy 88.265 204.47) (xy 88.265 215.9))
    (stroke (width 0) (type default))
  )
  (wire (pts (xy 141.605 216.535) (xy 141.605 213.36))
    (stroke (width 0) (type default))
  )
  (wire (pts (xy 52.07 139.7) (xy 50.165 139.7))
    (stroke (width 0) (type default))
  )
  (bus (pts (xy 100.33 110.49) (xy 100.33 111.76))
    (stroke (width 0) (type default))
  )

  (wire (pts (xy 176.53 121.92) (xy 180.34 121.92))
    (stroke (width 0) (type default))
  )
  (wire (pts (xy 278.13 104.14) (xy 278.13 111.76))
    (stroke (width 0) (type default))
  )
  (wire (pts (xy 80.01 116.84) (xy 97.79 116.84))
    (stroke (width 0) (type default))
  )
  (bus (pts (xy 100.33 134.62) (xy 100.33 137.16))
    (stroke (width 0) (type default))
  )

  (wire (pts (xy 176.53 58.42) (xy 197.612 58.42))
    (stroke (width 0) (type default))
  )
  (wire (pts (xy 302.26 83.82) (xy 275.59 83.82))
    (stroke (width 0) (type default))
  )
  (wire (pts (xy 80.01 68.58) (xy 104.14 68.58))
    (stroke (width 0) (type default))
  )
  (wire (pts (xy 275.59 142.24) (xy 278.13 142.24))
    (stroke (width 0) (type default))
  )
  (wire (pts (xy 245.11 147.32) (xy 245.11 157.48))
    (stroke (width 0) (type default))
  )
  (wire (pts (xy 404.114 63.5) (xy 372.11 63.5))
    (stroke (width 0) (type default))
  )
  (wire (pts (xy 52.07 40.64) (xy 25.4 40.64))
    (stroke (width 0) (type default))
  )
  (wire (pts (xy 52.07 45.72) (xy 25.4 45.72))
    (stroke (width 0) (type default))
  )
  (wire (pts (xy 404.114 91.44) (xy 372.11 91.44))
    (stroke (width 0) (type default))
  )
  (wire (pts (xy 340.36 101.6) (xy 344.17 101.6))
    (stroke (width 0) (type default))
  )
  (wire (pts (xy 148.59 53.34) (xy 125.095 53.34))
    (stroke (width 0) (type default))
  )
  (wire (pts (xy 372.11 40.64) (xy 375.92 40.64))
    (stroke (width 0) (type default))
  )
  (wire (pts (xy 176.53 129.54) (xy 194.31 129.54))
    (stroke (width 0) (type default))
  )
  (wire (pts (xy 247.65 121.92) (xy 224.282 121.92))
    (stroke (width 0) (type default))
  )
  (wire (pts (xy 146.05 147.32) (xy 146.05 149.86))
    (stroke (width 0) (type default))
  )
  (wire (pts (xy 80.01 167.64) (xy 91.44 167.64))
    (stroke (width 0) (type default))
  )
  (wire (pts (xy 247.65 127) (xy 224.282 127))
    (stroke (width 0) (type default))
  )
  (wire (pts (xy 317.5 81.28) (xy 344.17 81.28))
    (stroke (width 0) (type default))
  )
  (wire (pts (xy 372.11 43.18) (xy 375.92 43.18))
    (stroke (width 0) (type default))
  )
  (wire (pts (xy 129.54 114.3) (xy 148.59 114.3))
    (stroke (width 0) (type default))
  )
  (polyline (pts (xy 193.04 181.61) (xy 193.04 246.38))
    (stroke (width 0) (type default))
  )

  (wire (pts (xy 148.59 40.64) (xy 136.525 40.64))
    (stroke (width 0) (type default))
  )
  (wire (pts (xy 404.114 121.92) (xy 372.11 121.92))
    (stroke (width 0) (type default))
  )
  (wire (pts (xy 317.5 30.48) (xy 344.17 30.48))
    (stroke (width 0) (type default))
  )
  (wire (pts (xy 99.695 196.85) (xy 99.695 199.39))
    (stroke (width 0) (type default))
  )
  (wire (pts (xy 278.13 43.18) (xy 278.13 50.8))
    (stroke (width 0) (type default))
  )
  (wire (pts (xy 278.13 142.24) (xy 278.13 152.4))
    (stroke (width 0) (type default))
  )
  (wire (pts (xy 245.11 116.84) (xy 245.11 124.46))
    (stroke (width 0) (type default))
  )
  (wire (pts (xy 340.36 35.56) (xy 344.17 35.56))
    (stroke (width 0) (type default))
  )
  (wire (pts (xy 129.54 129.54) (xy 148.59 129.54))
    (stroke (width 0) (type default))
  )
  (wire (pts (xy 224.282 139.7) (xy 247.65 139.7))
    (stroke (width 0) (type default))
  )
  (wire (pts (xy 317.5 99.06) (xy 344.17 99.06))
    (stroke (width 0) (type default))
  )
  (wire (pts (xy 302.26 129.54) (xy 275.59 129.54))
    (stroke (width 0) (type default))
  )
  (wire (pts (xy 148.59 38.1) (xy 136.525 38.1))
    (stroke (width 0) (type default))
  )

  (text "optional\nlogic\ninverse*" (at 86.36 227.965 0)
    (effects (font (size 1 1)) (justify right bottom))
  )
  (text "*for logic inverse remove R177 and Q19" (at 160.02 245.11 0)
    (effects (font (size 1 1)) (justify left bottom))
  )
  (text "BOOT MODE: QUAD-SPI" (at 13.97 186.69 0)
    (effects (font (size 2.54 2.54) (thickness 0.508) bold) (justify left bottom))
  )
  (text "SOM decoupling" (at 232.918 187.706 0)
    (effects (font (size 2.54 2.54) (thickness 0.508) bold) (justify left bottom))
  )
  (text "FWUEN Button" (at 226.695 253.365 0)
    (effects (font (size 2.54 2.54) (thickness 0.508) bold) (justify left bottom))
  )
  (text "SOM K26 B2B connectors" (at 13.97 16.51 0)
    (effects (font (size 2.54 2.54) (thickness 0.508) bold) (justify left bottom))
  )
  (text "Standoffs" (at 110.49 249.555 0)
    (effects (font (size 1.27 1.27)) (justify left bottom))
  )
  (text "SHUTDOWN \npull-down" (at 198.12 192.024 0)
    (effects (font (size 2.54 2.54) (thickness 0.508) bold) (justify left bottom))
  )
  (text "5V Fan header" (at 78.74 186.69 0)
    (effects (font (size 2.54 2.54) (thickness 0.508) bold) (justify left bottom))
  )
  (text "Mechanical" (at 78.74 252.984 0)
    (effects (font (size 2.54 2.54) (thickness 0.508) bold) (justify left bottom))
  )
  (text "Test points" (at 347.98 189.23 0)
    (effects (font (size 2.54 2.54) (thickness 0.508) bold) (justify left bottom))
  )
  (text "SOM 3D Model" (at 203.2 260.985 0)
    (effects (font (size 1.27 1.27)) (justify left bottom))
  )

  (label "GTR_DP0_C2M_P" (at 25.4 162.56 0) (fields_autoplaced)
    (effects (font (size 1.27 1.27)) (justify left bottom))
  )
  (label "GTR_DP1_C2M_N" (at 121.92 165.1 0) (fields_autoplaced)
    (effects (font (size 1.27 1.27)) (justify left bottom))
  )
  (label "MIO76" (at 187.96 134.62 0) (fields_autoplaced)
    (effects (font (size 1.27 1.27)) (justify left bottom))
  )
  (label "HPC12_N" (at 317.5 114.3 0) (fields_autoplaced)
    (effects (font (size 1.27 1.27)) (justify left bottom))
  )
  (label "GTH_DP3_C2M_P" (at 404.114 35.56 180) (fields_autoplaced)
    (effects (font (size 1.27 1.27)) (justify right bottom))
  )
  (label "HDC02" (at 404.114 160.02 180) (fields_autoplaced)
    (effects (font (size 1.27 1.27)) (justify right bottom))
  )
  (label "MIO31_SHUTDOWN" (at 121.666 104.14 0) (fields_autoplaced)
    (effects (font (size 1.27 1.27)) (justify left bottom))
  )
  (label "HDA20" (at 81.28 230.505 0) (fields_autoplaced)
    (effects (font (size 1.27 1.27)) (justify left bottom))
  )
  (label "MIO64" (at 187.96 124.46 0) (fields_autoplaced)
    (effects (font (size 1.27 1.27)) (justify left bottom))
  )
  (label "MIO12_FWUEN_C2M_L" (at 283.845 265.43 180) (fields_autoplaced)
    (effects (font (size 1.27 1.27)) (justify right bottom))
  )
  (label "HPB17_P" (at 404.114 83.82 180) (fields_autoplaced)
    (effects (font (size 1.27 1.27)) (justify right bottom))
  )
  (label "HDA06" (at 130.81 68.58 0) (fields_autoplaced)
    (effects (font (size 1.27 1.27)) (justify left bottom))
  )
  (label "GTH_DP2_C2M_P" (at 302.26 25.4 180) (fields_autoplaced)
    (effects (font (size 1.27 1.27)) (justify right bottom))
  )
  (label "GTH_REFCLK0_C2M_N" (at 317.5 33.02 0) (fields_autoplaced)
    (effects (font (size 1.27 1.27)) (justify left bottom))
  )
  (label "HDC09" (at 317.5 170.18 0) (fields_autoplaced)
    (effects (font (size 1.27 1.27)) (justify left bottom))
  )
  (label "HPB01_P" (at 404.114 53.34 180) (fields_autoplaced)
    (effects (font (size 1.27 1.27)) (justify right bottom))
  )
  (label "GTH_DP0_C2M_P" (at 302.26 45.72 180) (fields_autoplaced)
    (effects (font (size 1.27 1.27)) (justify right bottom))
  )
  (label "MIO67" (at 137.16 129.54 180) (fields_autoplaced)
    (effects (font (size 1.27 1.27)) (justify right bottom))
  )
  (label "HPC02_N" (at 404.114 116.84 180) (fields_autoplaced)
    (effects (font (size 1.27 1.27)) (justify right bottom))
  )
  (label "HDA13" (at 187.96 76.2 0) (fields_autoplaced)
    (effects (font (size 1.27 1.27)) (justify left bottom))
  )
  (label "MIO35_WD_OUT" (at 356.235 218.44 0) (fields_autoplaced)
    (effects (font (size 1.27 1.27)) (justify left bottom))
  )
  (label "HPB03_P" (at 302.26 83.82 180) (fields_autoplaced)
    (effects (font (size 1.27 1.27)) (justify right bottom))
  )
  (label "HPB05_CC_P" (at 302.26 68.58 180) (fields_autoplaced)
    (effects (font (size 1.27 1.27)) (justify right bottom))
  )
  (label "HPC16_N" (at 302.26 109.22 180) (fields_autoplaced)
    (effects (font (size 1.27 1.27)) (justify right bottom))
  )
  (label "HPB_18_P" (at 317.5 81.28 0) (fields_autoplaced)
    (effects (font (size 1.27 1.27)) (justify left bottom))
  )
  (label "MIO68" (at 137.16 132.08 180) (fields_autoplaced)
    (effects (font (size 1.27 1.27)) (justify right bottom))
  )
  (label "PWR_GD_PL_M2C" (at 203.962 88.9 180) (fields_autoplaced)
    (effects (font (size 1.27 1.27)) (justify right bottom))
  )
  (label "HDB02" (at 404.114 139.7 180) (fields_autoplaced)
    (effects (font (size 1.27 1.27)) (justify right bottom))
  )
  (label "PWRGD_FPD_M2C" (at 203.962 83.82 180) (fields_autoplaced)
    (effects (font (size 1.27 1.27)) (justify right bottom))
  )
  (label "MIO71" (at 91.44 137.16 0) (fields_autoplaced)
    (effects (font (size 1.27 1.27)) (justify left bottom))
  )
  (label "PWROFF_C2M_L" (at 110.49 88.9 180) (fields_autoplaced)
    (effects (font (size 1.27 1.27)) (justify right bottom))
  )
  (label "HPC14_P" (at 224.282 111.76 0) (fields_autoplaced)
    (effects (font (size 1.27 1.27)) (justify left bottom))
  )
  (label "HPC08_N" (at 224.282 99.06 0) (fields_autoplaced)
    (effects (font (size 1.27 1.27)) (justify left bottom))
  )
  (label "GTH_REFCLK1_C2M_N" (at 224.282 43.18 0) (fields_autoplaced)
    (effects (font (size 1.27 1.27)) (justify left bottom))
  )
  (label "HDB04" (at 404.114 147.32 180) (fields_autoplaced)
    (effects (font (size 1.27 1.27)) (justify right bottom))
  )
  (label "MIO35_WD_OUT" (at 110.236 93.98 180) (fields_autoplaced)
    (effects (font (size 1.27 1.27)) (justify right bottom))
  )
  (label "HDC14" (at 302.26 160.02 180) (fields_autoplaced)
    (effects (font (size 1.27 1.27)) (justify right bottom))
  )
  (label "HPC00_CC_P" (at 404.114 106.68 180) (fields_autoplaced)
    (effects (font (size 1.27 1.27)) (justify right bottom))
  )
  (label "HDC10" (at 317.5 172.72 0) (fields_autoplaced)
    (effects (font (size 1.27 1.27)) (justify left bottom))
  )
  (label "HPB06_N" (at 224.282 76.2 0) (fields_autoplaced)
    (effects (font (size 1.27 1.27)) (justify left bottom))
  )
  (label "HDA05" (at 104.14 68.58 180) (fields_autoplaced)
    (effects (font (size 1.27 1.27)) (justify right bottom))
  )
  (label "MIO55" (at 137.16 119.38 180) (fields_autoplaced)
    (effects (font (size 1.27 1.27)) (justify right bottom))
  )
  (label "PWRGD_FPD_M2C" (at 356.235 208.28 0) (fields_autoplaced)
    (effects (font (size 1.27 1.27)) (justify left bottom))
  )
  (label "HDB20" (at 224.282 144.78 0) (fields_autoplaced)
    (effects (font (size 1.27 1.27)) (justify left bottom))
  )
  (label "GTH_DP1_C2M_P" (at 404.114 25.4 180) (fields_autoplaced)
    (effects (font (size 1.27 1.27)) (justify right bottom))
  )
  (label "HPB17_N" (at 404.114 86.36 180) (fields_autoplaced)
    (effects (font (size 1.27 1.27)) (justify right bottom))
  )
  (label "HPB09_P" (at 317.246 50.8 0) (fields_autoplaced)
    (effects (font (size 1.27 1.27)) (justify left bottom))
  )
  (label "MIO72" (at 91.44 139.7 0) (fields_autoplaced)
    (effects (font (size 1.27 1.27)) (justify left bottom))
  )
  (label "HPB07_P" (at 302.26 60.96 180) (fields_autoplaced)
    (effects (font (size 1.27 1.27)) (justify right bottom))
  )
  (label "MODE0_C2M" (at 19.685 192.405 0) (fields_autoplaced)
    (effects (font (size 1.27 1.27)) (justify left bottom))
  )
  (label "HPB13_P" (at 317.5 73.66 0) (fields_autoplaced)
    (effects (font (size 1.27 1.27)) (justify left bottom))
  )
  (label "HDC06" (at 317.5 160.02 0) (fields_autoplaced)
    (effects (font (size 1.27 1.27)) (justify left bottom))
  )
  (label "HDC12" (at 302.26 154.94 180) (fields_autoplaced)
    (effects (font (size 1.27 1.27)) (justify right bottom))
  )
  (label "HPB11_P" (at 302.26 76.2 180) (fields_autoplaced)
    (effects (font (size 1.27 1.27)) (justify right bottom))
  )
  (label "HDB08_CC" (at 317.5 144.78 0) (fields_autoplaced)
    (effects (font (size 1.27 1.27)) (justify left bottom))
  )
  (label "MIO50" (at 91.44 114.3 0) (fields_autoplaced)
    (effects (font (size 1.27 1.27)) (justify left bottom))
  )
  (label "HDA12" (at 187.96 73.66 0) (fields_autoplaced)
    (effects (font (size 1.27 1.27)) (justify left bottom))
  )
  (label "HPC16_P" (at 302.26 106.68 180) (fields_autoplaced)
    (effects (font (size 1.27 1.27)) (justify right bottom))
  )
  (label "HPA12_P" (at 25.4 45.72 0) (fields_autoplaced)
    (effects (font (size 1.27 1.27)) (justify left bottom))
  )
  (label "HPC03_P" (at 224.282 127 0) (fields_autoplaced)
    (effects (font (size 1.27 1.27)) (justify left bottom))
  )
  (label "HDC11" (at 317.5 175.26 0) (fields_autoplaced)
    (effects (font (size 1.27 1.27)) (justify left bottom))
  )
  (label "HDB05" (at 404.114 149.86 180) (fields_autoplaced)
    (effects (font (size 1.27 1.27)) (justify right bottom))
  )
  (label "MIO12_FWUEN_C2M_L" (at 121.666 93.98 0) (fields_autoplaced)
    (effects (font (size 1.27 1.27)) (justify left bottom))
  )
  (label "GTH_REFCLK1_C2M_P" (at 224.282 40.64 0) (fields_autoplaced)
    (effects (font (size 1.27 1.27)) (justify left bottom))
  )
  (label "PWRGD_LPD_M2C" (at 203.962 86.36 180) (fields_autoplaced)
    (effects (font (size 1.27 1.27)) (justify right bottom))
  )
  (label "HPB10_CC_N" (at 302.26 55.88 180) (fields_autoplaced)
    (effects (font (size 1.27 1.27)) (justify right bottom))
  )
  (label "MIO62" (at 40.64 121.92 180) (fields_autoplaced)
    (effects (font (size 1.27 1.27)) (justify right bottom))
  )
  (label "MIO27" (at 187.96 96.52 0) (fields_autoplaced)
    (effects (font (size 1.27 1.27)) (justify left bottom))
  )
  (label "HPC_CLK0_N" (at 317.5 129.54 0) (fields_autoplaced)
    (effects (font (size 1.27 1.27)) (justify left bottom))
  )
  (label "HPB02_P" (at 317.5 66.04 0) (fields_autoplaced)
    (effects (font (size 1.27 1.27)) (justify left bottom))
  )
  (label "HPC17_N" (at 317.5 91.44 0) (fields_autoplaced)
    (effects (font (size 1.27 1.27)) (justify left bottom))
  )
  (label "HPB14_P" (at 317.5 58.42 0) (fields_autoplaced)
    (effects (font (size 1.27 1.27)) (justify left bottom))
  )
  (label "HDC23" (at 224.282 175.26 0) (fields_autoplaced)
    (effects (font (size 1.27 1.27)) (justify left bottom))
  )
  (label "VCCO_HDC_1" (at 404.495 172.72 180) (fields_autoplaced)
    (effects (font (size 1.27 1.27)) (justify right bottom))
  )
  (label "HDA11" (at 40.64 66.04 180) (fields_autoplaced)
    (effects (font (size 1.27 1.27)) (justify right bottom))
  )
  (label "HPA14_P" (at 197.612 55.88 180) (fields_autoplaced)
    (effects (font (size 1.27 1.27)) (justify right bottom))
  )
  (label "MIO28" (at 187.96 99.06 0) (fields_autoplaced)
    (effects (font (size 1.27 1.27)) (justify left bottom))
  )
  (label "MIO29" (at 137.16 99.06 180) (fields_autoplaced)
    (effects (font (size 1.27 1.27)) (justify right bottom))
  )
  (label "MIO26" (at 194.056 93.98 180) (fields_autoplaced)
    (effects (font (size 1.27 1.27)) (justify right bottom))
  )
  (label "MIO66" (at 187.96 129.54 0) (fields_autoplaced)
    (effects (font (size 1.27 1.27)) (justify left bottom))
  )
  (label "HPB12_P" (at 224.282 66.04 0) (fields_autoplaced)
    (effects (font (size 1.27 1.27)) (justify left bottom))
  )
  (label "HPC00_CC_N" (at 404.114 109.22 180) (fields_autoplaced)
    (effects (font (size 1.27 1.27)) (justify right bottom))
  )
  (label "HPB10_CC_P" (at 302.26 53.34 180) (fields_autoplaced)
    (effects (font (size 1.27 1.27)) (justify right bottom))
  )
  (label "HPA10_CC_N" (at 125.095 55.88 0) (fields_autoplaced)
    (effects (font (size 1.27 1.27)) (justify left bottom))
  )
  (label "HDC18" (at 224.282 160.02 0) (fields_autoplaced)
    (effects (font (size 1.27 1.27)) (justify left bottom))
  )
  (label "HPC07_N" (at 302.26 116.84 180) (fields_autoplaced)
    (effects (font (size 1.27 1.27)) (justify right bottom))
  )
  (label "HDC01" (at 404.114 157.48 180) (fields_autoplaced)
    (effects (font (size 1.27 1.27)) (justify right bottom))
  )
  (label "HPC11_N" (at 317.5 106.68 0) (fields_autoplaced)
    (effects (font (size 1.27 1.27)) (justify left bottom))
  )
  (label "HPB15_CC_P" (at 224.282 50.8 0) (fields_autoplaced)
    (effects (font (size 1.27 1.27)) (justify left bottom))
  )
  (label "GTH_DP3_C2M_N" (at 404.114 38.1 180) (fields_autoplaced)
    (effects (font (size 1.27 1.27)) (justify right bottom))
  )
  (label "MIO52" (at 187.96 114.3 0) (fields_autoplaced)
    (effects (font (size 1.27 1.27)) (justify left bottom))
  )
  (label "HPC01_P" (at 404.114 99.06 180) (fields_autoplaced)
    (effects (font (size 1.27 1.27)) (justify right bottom))
  )
  (label "MIO51" (at 91.44 116.84 0) (fields_autoplaced)
    (effects (font (size 1.27 1.27)) (justify left bottom))
  )
  (label "GTH_DP0_M2C_P" (at 404.114 45.72 180) (fields_autoplaced)
    (effects (font (size 1.27 1.27)) (justify right bottom))
  )
  (label "HDB07" (at 317.5 142.24 0) (fields_autoplaced)
    (effects (font (size 1.27 1.27)) (justify left bottom))
  )
  (label "HPC18_P" (at 302.26 121.92 180) (fields_autoplaced)
    (effects (font (size 1.27 1.27)) (justify right bottom))
  )
  (label "HPC15_CC_N" (at 224.282 121.92 0) (fields_autoplaced)
    (effects (font (size 1.27 1.27)) (justify left bottom))
  )
  (label "HDB10" (at 317.5 152.4 0) (fields_autoplaced)
    (effects (font (size 1.27 1.27)) (justify left bottom))
  )
  (label "HPB16_P" (at 224.282 81.28 0) (fields_autoplaced)
    (effects (font (size 1.27 1.27)) (justify left bottom))
  )
  (label "VCCO_HDB_1" (at 302.26 172.72 180) (fields_autoplaced)
    (effects (font (size 1.27 1.27)) (justify right bottom))
  )
  (label "HPC06_N" (at 302.26 93.98 180) (fields_autoplaced)
    (effects (font (size 1.27 1.27)) (justify right bottom))
  )
  (label "HPB19_P" (at 224.282 88.9 0) (fields_autoplaced)
    (effects (font (size 1.27 1.27)) (justify left bottom))
  )
  (label "HDA20" (at 130.81 83.82 0) (fields_autoplaced)
    (effects (font (size 1.27 1.27)) (justify left bottom))
  )
  (label "HDA18" (at 137.16 78.74 180) (fields_autoplaced)
    (effects (font (size 1.27 1.27)) (justify right bottom))
  )
  (label "HPA11_P" (at 104.14 48.26 180) (fields_autoplaced)
    (effects (font (size 1.27 1.27)) (justify right bottom))
  )
  (label "HPB02_N" (at 317.5 68.58 0) (fields_autoplaced)
    (effects (font (size 1.27 1.27)) (justify left bottom))
  )
  (label "HPB16_N" (at 224.282 83.82 0) (fields_autoplaced)
    (effects (font (size 1.27 1.27)) (justify left bottom))
  )
  (label "HPB13_N" (at 317.5 76.2 0) (fields_autoplaced)
    (effects (font (size 1.27 1.27)) (justify left bottom))
  )
  (label "HPA10_CC_P" (at 125.095 53.34 0) (fields_autoplaced)
    (effects (font (size 1.27 1.27)) (justify left bottom))
  )
  (label "VCCO_HPB_1" (at 224.282 134.62 0) (fields_autoplaced)
    (effects (font (size 1.27 1.27)) (justify left bottom))
  )
  (label "HDA19" (at 130.81 81.28 0) (fields_autoplaced)
    (effects (font (size 1.27 1.27)) (justify left bottom))
  )
  (label "HPA06_CLK0_P" (at 25.4 38.1 0) (fields_autoplaced)
    (effects (font (size 1.27 1.27)) (justify left bottom))
  )
  (label "HPC05_CC_N" (at 317.5 121.92 0) (fields_autoplaced)
    (effects (font (size 1.27 1.27)) (justify left bottom))
  )
  (label "HPC13_P" (at 302.26 99.06 180) (fields_autoplaced)
    (effects (font (size 1.27 1.27)) (justify right bottom))
  )
  (label "GTH_DP1_C2M_N" (at 404.114 27.94 180) (fields_autoplaced)
    (effects (font (size 1.27 1.27)) (justify right bottom))
  )
  (label "HPC13_N" (at 302.26 101.6 180) (fields_autoplaced)
    (effects (font (size 1.27 1.27)) (justify right bottom))
  )
  (label "HDB15" (at 302.26 144.78 180) (fields_autoplaced)
    (effects (font (size 1.27 1.27)) (justify right bottom))
  )
  (label "PS_ERROR_STATUS_M2C" (at 110.49 86.36 180) (fields_autoplaced)
    (effects (font (size 1.27 1.27)) (justify right bottom))
  )
  (label "HDB03" (at 404.114 144.78 180) (fields_autoplaced)
    (effects (font (size 1.27 1.27)) (justify right bottom))
  )
  (label "HPB00_CC_N" (at 404.114 63.5 180) (fields_autoplaced)
    (effects (font (size 1.27 1.27)) (justify right bottom))
  )
  (label "HPC10_CC_N" (at 317.5 99.06 0) (fields_autoplaced)
    (effects (font (size 1.27 1.27)) (justify left bottom))
  )
  (label "GTH_DP2_C2M_N" (at 302.26 27.94 180) (fields_autoplaced)
    (effects (font (size 1.27 1.27)) (justify right bottom))
  )
  (label "GTH_REFCLK0_C2M_P" (at 317.5 30.48 0) (fields_autoplaced)
    (effects (font (size 1.27 1.27)) (justify left bottom))
  )
  (label "HPB_CLK0_P" (at 404.114 68.58 180) (fields_autoplaced)
    (effects (font (size 1.27 1.27)) (justify right bottom))
  )
  (label "GTH_DP0_M2C_N" (at 404.114 48.26 180) (fields_autoplaced)
    (effects (font (size 1.27 1.27)) (justify right bottom))
  )
  (label "MIO75" (at 40.64 134.62 180) (fields_autoplaced)
    (effects (font (size 1.27 1.27)) (justify right bottom))
  )
  (label "GTH_DP3_M2C_N" (at 224.282 33.02 0) (fields_autoplaced)
    (effects (font (size 1.27 1.27)) (justify left bottom))
  )
  (label "HPB_18_N" (at 317.5 83.82 0) (fields_autoplaced)
    (effects (font (size 1.27 1.27)) (justify left bottom))
  )
  (label "HPA14_N" (at 197.612 58.42 180) (fields_autoplaced)
    (effects (font (size 1.27 1.27)) (justify right bottom))
  )
  (label "GTH_DP3_M2C_P" (at 224.282 30.48 0) (fields_autoplaced)
    (effects (font (size 1.27 1.27)) (justify left bottom))
  )
  (label "MODE2_C2M" (at 19.685 197.485 0) (fields_autoplaced)
    (effects (font (size 1.27 1.27)) (justify left bottom))
  )
  (label "HDC07" (at 317.5 162.56 0) (fields_autoplaced)
    (effects (font (size 1.27 1.27)) (justify left bottom))
  )
  (label "HDB11" (at 317.5 154.94 0) (fields_autoplaced)
    (effects (font (size 1.27 1.27)) (justify left bottom))
  )
  (label "HPC09_N" (at 404.114 93.98 180) (fields_autoplaced)
    (effects (font (size 1.27 1.27)) (justify right bottom))
  )
  (label "HPB08_P" (at 224.282 58.42 0) (fields_autoplaced)
    (effects (font (size 1.27 1.27)) (justify left bottom))
  )
  (label "HPC14_N" (at 224.282 114.3 0) (fields_autoplaced)
    (effects (font (size 1.27 1.27)) (justify left bottom))
  )
  (label "HDB01" (at 404.114 137.16 180) (fields_autoplaced)
    (effects (font (size 1.27 1.27)) (justify right bottom))
  )
  (label "HDC19" (at 224.282 162.56 0) (fields_autoplaced)
    (effects (font (size 1.27 1.27)) (justify left bottom))
  )
  (label "HDB00_CC" (at 404.114 134.62 180) (fields_autoplaced)
    (effects (font (size 1.27 1.27)) (justify right bottom))
  )
  (label "MIO46" (at 187.96 109.22 0) (fields_autoplaced)
    (effects (font (size 1.27 1.27)) (justify left bottom))
  )
  (label "GTR_DP1_C2M_P" (at 121.92 162.56 0) (fields_autoplaced)
    (effects (font (size 1.27 1.27)) (justify left bottom))
  )
  (label "HDA08_CC" (at 130.81 73.66 0) (fields_autoplaced)
    (effects (font (size 1.27 1.27)) (justify left bottom))
  )
  (label "VCCO_HPC_1" (at 317.5 134.62 0) (fields_autoplaced)
    (effects (font (size 1.27 1.27)) (justify left bottom))
  )
  (label "MIO56" (at 137.16 121.92 180) (fields_autoplaced)
    (effects (font (size 1.27 1.27)) (justify right bottom))
  )
  (label "HDC05" (at 404.114 170.18 180) (fields_autoplaced)
    (effects (font (size 1.27 1.27)) (justify right bottom))
  )
  (label "HPB_CLK0_N" (at 404.114 71.12 180) (fields_autoplaced)
    (effects (font (size 1.27 1.27)) (justify right bottom))
  )
  (label "MIO49" (at 137.16 114.3 180) (fields_autoplaced)
    (effects (font (size 1.27 1.27)) (justify right bottom))
  )
  (label "MODE2_C2M" (at 25.4 96.52 0) (fields_autoplaced)
    (effects (font (size 1.27 1.27)) (justify left bottom))
  )
  (label "MIO31_SHUTDOWN" (at 195.453 207.772 0) (fields_autoplaced)
    (effects (font (size 1.27 1.27)) (justify left bottom))
  )
  (label "HDC15" (at 302.26 165.1 180) (fields_autoplaced)
    (effects (font (size 1.27 1.27)) (justify right bottom))
  )
  (label "MIO57" (at 137.16 124.46 180) (fields_autoplaced)
    (effects (font (size 1.27 1.27)) (justify right bottom))
  )
  (label "GTH_DP1_M2C_N" (at 317.5 43.18 0) (fields_autoplaced)
    (effects (font (size 1.27 1.27)) (justify left bottom))
  )
  (label "PWROFF_C2M_L" (at 356.235 205.74 0) (fields_autoplaced)
    (effects (font (size 1.27 1.27)) (justify left bottom))
  )
  (label "VCCO_HPB_2" (at 302.26 129.54 180) (fields_autoplaced)
    (effects (font (size 1.27 1.27)) (justify right bottom))
  )
  (label "MIO77" (at 187.96 137.16 0) (fields_autoplaced)
    (effects (font (size 1.27 1.27)) (justify left bottom))
  )
  (label "MIO40" (at 98.552 109.22 180) (fields_autoplaced)
    (effects (font (size 1.27 1.27)) (justify right bottom))
  )
  (label "MIO63" (at 40.64 124.46 180) (fields_autoplaced)
    (effects (font (size 1.27 1.27)) (justify right bottom))
  )
  (label "MIO47" (at 137.16 109.22 180) (fields_autoplaced)
    (effects (font (size 1.27 1.27)) (justify right bottom))
  )
  (label "GTH_DP1_M2C_P" (at 317.5 40.64 0) (fields_autoplaced)
    (effects (font (size 1.27 1.27)) (justify left bottom))
  )
  (label "HDB22" (at 224.282 152.4 0) (fields_autoplaced)
    (effects (font (size 1.27 1.27)) (justify left bottom))
  )
  (label "PS_ERROR_OUT_M2C" (at 110.49 83.82 180) (fields_autoplaced)
    (effects (font (size 1.27 1.27)) (justify right bottom))
  )
  (label "HDB19" (at 224.282 142.24 0) (fields_autoplaced)
    (effects (font (size 1.27 1.27)) (justify left bottom))
  )
  (label "HPC18_N" (at 302.26 124.46 180) (fields_autoplaced)
    (effects (font (size 1.27 1.27)) (justify right bottom))
  )
  (label "HPB03_N" (at 302.26 86.36 180) (fields_autoplaced)
    (effects (font (size 1.27 1.27)) (justify right bottom))
  )
  (label "HPC12_P" (at 317.5 111.76 0) (fields_autoplaced)
    (effects (font (size 1.27 1.27)) (justify left bottom))
  )
  (label "HPC15_CC_P" (at 224.282 119.38 0) (fields_autoplaced)
    (effects (font (size 1.27 1.27)) (justify left bottom))
  )
  (label "HPB12_N" (at 224.282 68.58 0) (fields_autoplaced)
    (effects (font (size 1.27 1.27)) (justify left bottom))
  )
  (label "MIO54" (at 187.96 119.38 0) (fields_autoplaced)
    (effects (font (size 1.27 1.27)) (justify left bottom))
  )
  (label "HDC04" (at 404.114 167.64 180) (fields_autoplaced)
    (effects (font (size 1.27 1.27)) (justify right bottom))
  )
  (label "HPB14_N" (at 317.5 60.96 0) (fields_autoplaced)
    (effects (font (size 1.27 1.27)) (justify left bottom))
  )
  (label "HDB21" (at 224.282 149.86 0) (fields_autoplaced)
    (effects (font (size 1.27 1.27)) (justify left bottom))
  )
  (label "HDB12" (at 302.26 134.62 180) (fields_autoplaced)
    (effects (font (size 1.27 1.27)) (justify right bottom))
  )
  (label "MIO26" (at 356.235 215.9 0) (fields_autoplaced)
    (effects (font (size 1.27 1.27)) (justify left bottom))
  )
  (label "HPC19_P" (at 224.282 104.14 0) (fields_autoplaced)
    (effects (font (size 1.27 1.27)) (justify left bottom))
  )
  (label "GTH_DP0_C2M_N" (at 302.26 48.26 180) (fields_autoplaced)
    (effects (font (size 1.27 1.27)) (justify right bottom))
  )
  (label "VCCO_HPC_2" (at 404.114 129.54 180) (fields_autoplaced)
    (effects (font (size 1.27 1.27)) (justify right bottom))
  )
  (label "MIO61" (at 40.64 119.38 180) (fields_autoplaced)
    (effects (font (size 1.27 1.27)) (justify right bottom))
  )
  (label "MODE1_C2M" (at 25.4 93.98 0) (fields_autoplaced)
    (effects (font (size 1.27 1.27)) (justify left bottom))
  )
  (label "HDA10" (at 34.29 63.5 0) (fields_autoplaced)
    (effects (font (size 1.27 1.27)) (justify left bottom))
  )
  (label "MIO45" (at 187.96 106.68 0) (fields_autoplaced)
    (effects (font (size 1.27 1.27)) (justify left bottom))
  )
  (label "MIO30" (at 137.16 101.6 180) (fields_autoplaced)
    (effects (font (size 1.27 1.27)) (justify right bottom))
  )
  (label "HDC08_CC" (at 317.5 165.1 0) (fields_autoplaced)
    (effects (font (size 1.27 1.27)) (justify left bottom))
  )
  (label "HPA13_N" (at 25.4 55.88 0) (fields_autoplaced)
    (effects (font (size 1.27 1.27)) (justify left bottom))
  )
  (label "MODE3_C2M" (at 19.685 200.025 0) (fields_autoplaced)
    (effects (font (size 1.27 1.27)) (justify left bottom))
  )
  (label "HPC10_CC_P" (at 317.5 96.52 0) (fields_autoplaced)
    (effects (font (size 1.27 1.27)) (justify left bottom))
  )
  (label "HDC03" (at 404.114 165.1 180) (fields_autoplaced)
    (effects (font (size 1.27 1.27)) (justify right bottom))
  )
  (label "HPB19_N" (at 224.282 91.44 0) (fields_autoplaced)
    (effects (font (size 1.27 1.27)) (justify left bottom))
  )
  (label "VCCO_HDB_2" (at 302.26 175.26 180) (fields_autoplaced)
    (effects (font (size 1.27 1.27)) (justify right bottom))
  )
  (label "HPC17_P" (at 317.5 88.9 0) (fields_autoplaced)
    (effects (font (size 1.27 1.27)) (justify left bottom))
  )
  (label "MIO58" (at 91.44 124.46 0) (fields_autoplaced)
    (effects (font (size 1.27 1.27)) (justify left bottom))
  )
  (label "GTR_DP0_C2M_N" (at 25.4 165.1 0) (fields_autoplaced)
    (effects (font (size 1.27 1.27)) (justify left bottom))
  )
  (label "HDB14" (at 302.26 139.7 180) (fields_autoplaced)
    (effects (font (size 1.27 1.27)) (justify right bottom))
  )
  (label "MIO74" (at 40.64 132.08 180) (fields_autoplaced)
    (effects (font (size 1.27 1.27)) (justify right bottom))
  )
  (label "HDB17" (at 302.26 149.86 180) (fields_autoplaced)
    (effects (font (size 1.27 1.27)) (justify right bottom))
  )
  (label "HDA07" (at 130.81 71.12 0) (fields_autoplaced)
    (effects (font (size 1.27 1.27)) (justify left bottom))
  )
  (label "HPA06_CLK0_N" (at 25.4 40.64 0) (fields_autoplaced)
    (effects (font (size 1.27 1.27)) (justify left bottom))
  )
  (label "HPC04_P" (at 404.114 121.92 180) (fields_autoplaced)
    (effects (font (size 1.27 1.27)) (justify right bottom))
  )
  (label "HPC08_P" (at 224.282 96.52 0) (fields_autoplaced)
    (effects (font (size 1.27 1.27)) (justify left bottom))
  )
  (label "HPC02_P" (at 404.114 114.3 180) (fields_autoplaced)
    (effects (font (size 1.27 1.27)) (justify right bottom))
  )
  (label "HPB04_N" (at 404.114 78.74 180) (fields_autoplaced)
    (effects (font (size 1.27 1.27)) (justify right bottom))
  )
  (label "PWR_GD_PL_M2C" (at 356.235 213.36 0) (fields_autoplaced)
    (effects (font (size 1.27 1.27)) (justify left bottom))
  )
  (label "HDB16_CC" (at 302.26 147.32 180) (fields_autoplaced)
    (effects (font (size 1.27 1.27)) (justify right bottom))
  )
  (label "HPB05_CC_N" (at 302.26 71.12 180) (fields_autoplaced)
    (effects (font (size 1.27 1.27)) (justify right bottom))
  )
  (label "MIO73" (at 40.64 129.54 180) (fields_autoplaced)
    (effects (font (size 1.27 1.27)) (justify right bottom))
  )
  (label "HDC21" (at 224.282 170.18 0) (fields_autoplaced)
    (effects (font (size 1.27 1.27)) (justify left bottom))
  )
  (label "HPB09_N" (at 317.5 53.34 0) (fields_autoplaced)
    (effects (font (size 1.27 1.27)) (justify left bottom))
  )
  (label "HPA13_P" (at 25.4 53.34 0) (fields_autoplaced)
    (effects (font (size 1.27 1.27)) (justify left bottom))
  )
  (label "VCCO_HDC_2" (at 404.495 175.26 180) (fields_autoplaced)
    (effects (font (size 1.27 1.27)) (justify right bottom))
  )
  (label "VCC_BATT" (at 25.4 25.4 0) (fields_autoplaced)
    (effects (font (size 1.27 1.27)) (justify left bottom))
  )
  (label "HDC17" (at 302.26 170.18 180) (fields_autoplaced)
    (effects (font (size 1.27 1.27)) (justify right bottom))
  )
  (label "HDC20" (at 224.282 165.1 0) (fields_autoplaced)
    (effects (font (size 1.27 1.27)) (justify left bottom))
  )
  (label "HPC11_P" (at 317.5 104.14 0) (fields_autoplaced)
    (effects (font (size 1.27 1.27)) (justify left bottom))
  )
  (label "HDC13" (at 302.26 157.48 180) (fields_autoplaced)
    (effects (font (size 1.27 1.27)) (justify right bottom))
  )
  (label "MIO48" (at 137.16 111.76 180) (fields_autoplaced)
    (effects (font (size 1.27 1.27)) (justify right bottom))
  )
  (label "HPC04_N" (at 404.114 124.46 180) (fields_autoplaced)
    (effects (font (size 1.27 1.27)) (justify right bottom))
  )
  (label "HDB18" (at 224.282 139.7 0) (fields_autoplaced)
    (effects (font (size 1.27 1.27)) (justify left bottom))
  )
  (label "MODE1_C2M" (at 19.685 194.945 0) (fields_autoplaced)
    (effects (font (size 1.27 1.27)) (justify left bottom))
  )
  (label "HPB04_P" (at 404.114 76.2 180) (fields_autoplaced)
    (effects (font (size 1.27 1.27)) (justify right bottom))
  )
  (label "HDC00_CC" (at 404.114 154.94 180) (fields_autoplaced)
    (effects (font (size 1.27 1.27)) (justify right bottom))
  )
  (label "HPC09_P" (at 404.114 91.44 180) (fields_autoplaced)
    (effects (font (size 1.27 1.27)) (justify right bottom))
  )
  (label "HPA11_N" (at 104.14 50.8 180) (fields_autoplaced)
    (effects (font (size 1.27 1.27)) (justify right bottom))
  )
  (label "HPC19_N" (at 224.282 106.68 0) (fields_autoplaced)
    (effects (font (size 1.27 1.27)) (justify left bottom))
  )
  (label "HPC03_N" (at 224.282 129.54 0) (fields_autoplaced)
    (effects (font (size 1.27 1.27)) (justify left bottom))
  )
  (label "PS_ERROR_OUT_M2C" (at 356.235 200.66 0) (fields_autoplaced)
    (effects (font (size 1.27 1.27)) (justify left bottom))
  )
  (label "HPC_CLK0_P" (at 317.5 127 0) (fields_autoplaced)
    (effects (font (size 1.27 1.27)) (justify left bottom))
  )
  (label "HPC05_CC_P" (at 317.5 119.38 0) (fields_autoplaced)
    (effects (font (size 1.27 1.27)) (justify left bottom))
  )
  (label "HDA03" (at 104.14 63.5 180) (fields_autoplaced)
    (effects (font (size 1.27 1.27)) (justify right bottom))
  )
  (label "HDB06" (at 317.5 139.7 0) (fields_autoplaced)
    (effects (font (size 1.27 1.27)) (justify left bottom))
  )
  (label "HDC22" (at 224.282 172.72 0) (fields_autoplaced)
    (effects (font (size 1.27 1.27)) (justify left bottom))
  )
  (label "PWRGD_LPD_M2C" (at 356.235 210.82 0) (fields_autoplaced)
    (effects (font (size 1.27 1.27)) (justify left bottom))
  )
  (label "HPB06_P" (at 224.282 73.66 0) (fields_autoplaced)
    (effects (font (size 1.27 1.27)) (justify left bottom))
  )
  (label "HPC06_P" (at 302.26 91.44 180) (fields_autoplaced)
    (effects (font (size 1.27 1.27)) (justify right bottom))
  )
  (label "MIO70" (at 91.44 134.62 0) (fields_autoplaced)
    (effects (font (size 1.27 1.27)) (justify left bottom))
  )
  (label "GTH_DP2_M2C_P" (at 302.26 35.56 180) (fields_autoplaced)
    (effects (font (size 1.27 1.27)) (justify right bottom))
  )
  (label "PS_ERROR_STATUS_M2C" (at 356.235 203.2 0) (fields_autoplaced)
    (effects (font (size 1.27 1.27)) (justify left bottom))
  )
  (label "HDA15" (at 94.996 73.66 0) (fields_autoplaced)
    (effects (font (size 1.27 1.27)) (justify left bottom))
  )
  (label "MIO59" (at 91.44 127 0) (fields_autoplaced)
    (effects (font (size 1.27 1.27)) (justify left bottom))
  )
  (label "HPB11_N" (at 302.26 78.74 180) (fields_autoplaced)
    (effects (font (size 1.27 1.27)) (justify right bottom))
  )
  (label "HPA12_N" (at 25.4 48.26 0) (fields_autoplaced)
    (effects (font (size 1.27 1.27)) (justify left bottom))
  )
  (label "HDB13" (at 302.26 137.16 180) (fields_autoplaced)
    (effects (font (size 1.27 1.27)) (justify right bottom))
  )
  (label "GTH_DP2_M2C_N" (at 302.26 38.1 180) (fields_autoplaced)
    (effects (font (size 1.27 1.27)) (justify right bottom))
  )
  (label "MIO69" (at 137.16 134.62 180) (fields_autoplaced)
    (effects (font (size 1.27 1.27)) (justify right bottom))
  )
  (label "HPB08_N" (at 224.282 60.96 0) (fields_autoplaced)
    (effects (font (size 1.27 1.27)) (justify left bottom))
  )
  (label "HPC01_N" (at 404.114 101.6 180) (fields_autoplaced)
    (effects (font (size 1.27 1.27)) (justify right bottom))
  )
  (label "HPC07_P" (at 302.26 114.3 180) (fields_autoplaced)
    (effects (font (size 1.27 1.27)) (justify right bottom))
  )
  (label "MIO53" (at 187.96 116.84 0) (fields_autoplaced)
    (effects (font (size 1.27 1.27)) (justify left bottom))
  )
  (label "HDC16_CC" (at 302.26 167.64 180) (fields_autoplaced)
    (effects (font (size 1.27 1.27)) (justify right bottom))
  )
  (label "HPB_15_CC_N" (at 224.282 53.34 0) (fields_autoplaced)
    (effects (font (size 1.27 1.27)) (justify left bottom))
  )
  (label "HDB23" (at 224.282 154.94 0) (fields_autoplaced)
    (effects (font (size 1.27 1.27)) (justify left bottom))
  )
  (label "MIO65" (at 187.96 127 0) (fields_autoplaced)
    (effects (font (size 1.27 1.27)) (justify left bottom))
  )
  (label "MIO60" (at 91.44 129.54 0) (fields_autoplaced)
    (effects (font (size 1.27 1.27)) (justify left bottom))
  )
  (label "MODE3_C2M" (at 25.4 99.06 0) (fields_autoplaced)
    (effects (font (size 1.27 1.27)) (justify left bottom))
  )
  (label "HPB07_N" (at 302.26 63.5 180) (fields_autoplaced)
    (effects (font (size 1.27 1.27)) (justify right bottom))
  )
  (label "HPB01_N" (at 404.114 55.88 180) (fields_autoplaced)
    (effects (font (size 1.27 1.27)) (justify right bottom))
  )
  (label "HDB09" (at 317.5 149.86 0) (fields_autoplaced)
    (effects (font (size 1.27 1.27)) (justify left bottom))
  )
  (label "HPB00_CC_P" (at 404.114 60.96 180) (fields_autoplaced)
    (effects (font (size 1.27 1.27)) (justify right bottom))
  )
  (label "HDA14" (at 187.96 78.74 0) (fields_autoplaced)
    (effects (font (size 1.27 1.27)) (justify left bottom))
  )
  (label "HDA17" (at 94.996 78.74 0) (fields_autoplaced)
    (effects (font (size 1.27 1.27)) (justify left bottom))
  )
  (label "MODE0_C2M" (at 25.4 91.44 0) (fields_autoplaced)
    (effects (font (size 1.27 1.27)) (justify left bottom))
  )

  (global_label "SOM_5V0" (shape input) (at 133.985 175.26 180) (fields_autoplaced)
    (effects (font (size 1.27 1.27)) (justify right))
    (property "Intersheetrefs" "${INTERSHEET_REFS}" (at 103.505 0 0)
      (effects (font (size 1.27 1.27)) hide)
    )
  )
  (global_label "PL_3V3" (shape input) (at 95.885 55.88 0) (fields_autoplaced)
    (effects (font (size 1.27 1.27)) (justify left))
    (property "Intersheetrefs" "${INTERSHEET_REFS}" (at -6.985 0 0)
      (effects (font (size 1.27 1.27)) hide)
    )
  )
  (global_label "PL_3V3" (shape input) (at 302.26 222.25 180) (fields_autoplaced)
    (effects (font (size 1.27 1.27)) (justify right))
    (property "Intersheetrefs" "${INTERSHEET_REFS}" (at 40.64 389.89 0)
      (effects (font (size 1.27 1.27)) hide)
    )
  )
  (global_label "SOM_5V0" (shape input) (at 184.15 175.26 0) (fields_autoplaced)
    (effects (font (size 1.27 1.27)) (justify left))
    (property "Intersheetrefs" "${INTERSHEET_REFS}" (at 214.63 350.52 0)
      (effects (font (size 1.27 1.27)) hide)
    )
  )
  (global_label "SOM_5V0" (shape input) (at 88.9 175.26 0) (fields_autoplaced)
    (effects (font (size 1.27 1.27)) (justify left))
    (property "Intersheetrefs" "${INTERSHEET_REFS}" (at 119.38 350.52 0)
      (effects (font (size 1.27 1.27)) hide)
    )
  )
  (global_label "PL_1V2" (shape input) (at 302.26 196.85 180) (fields_autoplaced)
    (effects (font (size 1.27 1.27)) (justify right))
    (property "Intersheetrefs" "${INTERSHEET_REFS}" (at 40.64 328.93 0)
      (effects (font (size 1.27 1.27)) hide)
    )
  )
  (global_label "SOM_5V0" (shape input) (at 245.11 196.85 180) (fields_autoplaced)
    (effects (font (size 1.27 1.27)) (justify right))
    (property "Intersheetrefs" "${INTERSHEET_REFS}" (at 220.98 -64.77 0)
      (effects (font (size 1.27 1.27)) hide)
    )
  )
  (global_label "SOM_5V0" (shape input) (at 42.545 175.26 180) (fields_autoplaced)
    (effects (font (size 1.27 1.27)) (justify right))
    (property "Intersheetrefs" "${INTERSHEET_REFS}" (at 12.065 0 0)
      (effects (font (size 1.27 1.27)) hide)
    )
  )
  (global_label "PL_1V2" (shape input) (at 191.135 25.4 0) (fields_autoplaced)
    (effects (font (size 1.27 1.27)) (justify left))
    (property "Intersheetrefs" "${INTERSHEET_REFS}" (at -8.255 -2.54 0)
      (effects (font (size 1.27 1.27)) hide)
    )
  )
  (global_label "USB_5V" (shape input) (at 86.995 196.85 180) (fields_autoplaced)
    (effects (font (size 1.27 1.27)) (justify right))
    (property "Intersheetrefs" "${INTERSHEET_REFS}" (at -5.715 0 0)
      (effects (font (size 1.27 1.27)) hide)
    )
  )
  (global_label "SOM_5V0" (shape input) (at 245.11 222.25 180) (fields_autoplaced)
    (effects (font (size 1.27 1.27)) (justify right))
    (property "Intersheetrefs" "${INTERSHEET_REFS}" (at -15.24 290.83 0)
      (effects (font (size 1.27 1.27)) hide)
    )
  )

  (hierarchical_label "HPA09_N" (shape input) (at 187.96 50.8 0) (fields_autoplaced)
    (effects (font (size 1.27 1.27)) (justify left))
  )
  (hierarchical_label "HDA[11..18]" (shape input) (at 198.12 69.85 0) (fields_autoplaced)
    (effects (font (size 1.27 1.27)) (justify left))
  )
  (hierarchical_label "MIO24_I2C_SCK" (shape input) (at 137.16 88.9 180) (fields_autoplaced)
    (effects (font (size 1.27 1.27)) (justify right))
  )
  (hierarchical_label "HPA05_CC_N" (shape input) (at 91.44 27.94 0) (fields_autoplaced)
    (effects (font (size 1.27 1.27)) (justify left))
  )
  (hierarchical_label "GTR_REFCLK3_C2M_P" (shape input) (at 40.64 152.4 180) (fields_autoplaced)
    (effects (font (size 1.27 1.27)) (justify right))
  )
  (hierarchical_label "JTAG_TMS_C2M" (shape input) (at 40.64 78.74 180) (fields_autoplaced)
    (effects (font (size 1.27 1.27)) (justify right))
  )
  (hierarchical_label "HPA03_P" (shape input) (at 136.525 38.1 180) (fields_autoplaced)
    (effects (font (size 1.27 1.27)) (justify right))
  )
  (hierarchical_label "HPA00_CC_N" (shape input) (at 134.874 33.02 180) (fields_autoplaced)
    (effects (font (size 1.27 1.27)) (justify right))
  )
  (hierarchical_label "HPA02_P" (shape input) (at 187.96 33.02 0) (fields_autoplaced)
    (effects (font (size 1.27 1.27)) (justify left))
  )
  (hierarchical_label "GTR_REFCLK0_C2M_P" (shape input) (at 137.16 142.24 180) (fields_autoplaced)
    (effects (font (size 1.27 1.27)) (justify right))
  )
  (hierarchical_label "MIO[64..77]" (shape input) (at 101.6 129.54 0) (fields_autoplaced)
    (effects (font (size 1.27 1.27)) (justify left))
  )
  (hierarchical_label "GTR_DP0_M2C_P" (shape input) (at 91.44 167.64 0) (fields_autoplaced)
    (effects (font (size 1.27 1.27)) (justify left))
  )
  (hierarchical_label "VCCO_EN_PS_M2C" (shape input) (at 40.64 71.12 180) (fields_autoplaced)
    (effects (font (size 1.27 1.27)) (justify right))
  )
  (hierarchical_label "GTR_DP2_M2C_P" (shape input) (at 187.96 167.64 0) (fields_autoplaced)
    (effects (font (size 1.27 1.27)) (justify left))
  )
  (hierarchical_label "HDA[11..18]" (shape input) (at 109.22 69.85 0) (fields_autoplaced)
    (effects (font (size 1.27 1.27)) (justify left))
  )
  (hierarchical_label "GTR_REFCLK1_C2M_N" (shape input) (at 91.44 149.86 0) (fields_autoplaced)
    (effects (font (size 1.27 1.27)) (justify left))
  )
  (hierarchical_label "HPA05_CC_P" (shape input) (at 91.44 25.4 0) (fields_autoplaced)
    (effects (font (size 1.27 1.27)) (justify left))
  )
  (hierarchical_label "GTR_DP2_C2M_P" (shape input) (at 91.44 157.48 0) (fields_autoplaced)
    (effects (font (size 1.27 1.27)) (justify left))
  )
  (hierarchical_label "GTR_DP1_M2C_N" (shape input) (at 40.64 144.78 180) (fields_autoplaced)
    (effects (font (size 1.27 1.27)) (justify right))
  )
  (hierarchical_label "HPA07_P" (shape input) (at 94.488 40.64 0) (fields_autoplaced)
    (effects (font (size 1.27 1.27)) (justify left))
  )
  (hierarchical_label "MIO[52..63]" (shape input) (at 30.48 114.3 180) (fields_autoplaced)
    (effects (font (size 1.27 1.27)) (justify right))
  )
  (hierarchical_label "HDA[11..18]" (shape input) (at 127 74.93 180) (fields_autoplaced)
    (effects (font (size 1.27 1.27)) (justify right))
  )
  (hierarchical_label "MIO[45..51]" (shape input) (at 101.6 110.49 0) (fields_autoplaced)
    (effects (font (size 1.27 1.27)) (justify left))
  )
  (hierarchical_label "MIO[27..30]" (shape input) (at 125.73 95.25 180) (fields_autoplaced)
    (effects (font (size 1.27 1.27)) (justify right))
  )
  (hierarchical_label "~{PS_POR}" (shape input) (at 137.16 60.96 180) (fields_autoplaced)
    (effects (font (size 1.27 1.27)) (justify right))
  )
  (hierarchical_label "GTR_DP3_M2C_N" (shape input) (at 137.16 154.94 180) (fields_autoplaced)
    (effects (font (size 1.27 1.27)) (justify right))
  )
  (hierarchical_label "HPA07_N" (shape input) (at 94.488 43.18 0) (fields_autoplaced)
    (effects (font (size 1.27 1.27)) (justify left))
  )
  (hierarchical_label "MIO[64..77]" (shape input) (at 199.39 119.38 0) (fields_autoplaced)
    (effects (font (size 1.27 1.27)) (justify left))
  )
  (hierarchical_label "HPA01_N" (shape input) (at 187.96 43.18 0) (fields_autoplaced)
    (effects (font (size 1.27 1.27)) (justify left))
  )
  (hierarchical_label "MIO36" (shape input) (at 91.44 96.52 0) (fields_autoplaced)
    (effects (font (size 1.27 1.27)) (justify left))
  )
  (hierarchical_label "MIO[45..51]" (shape input) (at 198.12 102.87 0) (fields_autoplaced)
    (effects (font (size 1.27 1.27)) (justify left))
  )
  (hierarchical_label "HPA04_P" (shape input) (at 94.488 33.02 0) (fields_autoplaced)
    (effects (font (size 1.27 1.27)) (justify left))
  )
  (hierarchical_label "MIO[64..77]" (shape input) (at 125.73 124.46 180) (fields_autoplaced)
    (effects (font (size 1.27 1.27)) (justify right))
  )
  (hierarchical_label "HPA01_P" (shape input) (at 187.96 40.64 0) (fields_autoplaced)
    (effects (font (size 1.27 1.27)) (justify left))
  )
  (hierarchical_label "GTR_REFCLK2_C2M_N" (shape input) (at 187.96 160.02 0) (fields_autoplaced)
    (effects (font (size 1.27 1.27)) (justify left))
  )
  (hierarchical_label "GTR_DP2_C2M_N" (shape input) (at 91.44 160.02 0) (fields_autoplaced)
    (effects (font (size 1.27 1.27)) (justify left))
  )
  (hierarchical_label "GTR_REFCLK3_C2M_N" (shape input) (at 40.64 154.94 180) (fields_autoplaced)
    (effects (font (size 1.27 1.27)) (justify right))
  )
  (hierarchical_label "GTR_REFCLK2_C2M_P" (shape input) (at 187.96 157.48 0) (fields_autoplaced)
    (effects (font (size 1.27 1.27)) (justify left))
  )
  (hierarchical_label "GTR_DP3_M2C_P" (shape input) (at 137.16 152.4 180) (fields_autoplaced)
    (effects (font (size 1.27 1.27)) (justify right))
  )
  (hierarchical_label "JTAG_TDI_C2M" (shape input) (at 40.64 83.82 180) (fields_autoplaced)
    (effects (font (size 1.27 1.27)) (justify right))
  )
  (hierarchical_label "HPA09_P" (shape input) (at 187.96 48.26 0) (fields_autoplaced)
    (effects (font (size 1.27 1.27)) (justify left))
  )
  (hierarchical_label "GTR_DP0_M2C_N" (shape input) (at 91.44 170.18 0) (fields_autoplaced)
    (effects (font (size 1.27 1.27)) (justify left))
  )
  (hierarchical_label "~{PS_SRST_C2M}" (shape input) (at 137.16 63.5 180) (fields_autoplaced)
    (effects (font (size 1.27 1.27)) (justify right))
  )
  (hierarchical_label "HPA03_N" (shape input) (at 136.525 40.64 180) (fields_autoplaced)
    (effects (font (size 1.27 1.27)) (justify right))
  )
  (hierarchical_label "HPA06_P" (shape input) (at 40.64 30.48 180) (fields_autoplaced)
    (effects (font (size 1.27 1.27)) (justify right))
  )
  (hierarchical_label "MIO39" (shape input) (at 91.44 106.68 0) (fields_autoplaced)
    (effects (font (size 1.27 1.27)) (justify left))
  )
  (hierarchical_label "MIO[45..51]" (shape input) (at 125.73 105.41 180) (fields_autoplaced)
    (effects (font (size 1.27 1.27)) (justify right))
  )
  (hierarchical_label "HDA[11..18]" (shape input) (at 29.21 62.23 180) (fields_autoplaced)
    (effects (font (size 1.27 1.27)) (justify right))
  )
  (hierarchical_label "HDA16_CC" (shape input) (at 93.472 76.2 0) (fields_autoplaced)
    (effects (font (size 1.27 1.27)) (justify left))
  )
  (hierarchical_label "GTR_DP3_C2M_N" (shape input) (at 187.96 149.86 0) (fields_autoplaced)
    (effects (font (size 1.27 1.27)) (justify left))
  )
  (hierarchical_label "HPA06_N" (shape input) (at 40.64 33.02 180) (fields_autoplaced)
    (effects (font (size 1.27 1.27)) (justify right))
  )
  (hierarchical_label "GTR_DP2_M2C_N" (shape input) (at 187.96 170.18 0) (fields_autoplaced)
    (effects (font (size 1.27 1.27)) (justify left))
  )
  (hierarchical_label "MIO42" (shape input) (at 40.64 111.76 180) (fields_autoplaced)
    (effects (font (size 1.27 1.27)) (justify right))
  )
  (hierarchical_label "VCCO_EN_PL_M2C" (shape input) (at 40.64 73.66 180) (fields_autoplaced)
    (effects (font (size 1.27 1.27)) (justify right))
  )
  (hierarchical_label "HDA04" (shape input) (at 96.774 66.04 0) (fields_autoplaced)
    (effects (font (size 1.27 1.27)) (justify left))
  )
  (hierarchical_label "HPA02_N" (shape input) (at 187.96 35.56 0) (fields_autoplaced)
    (effects (font (size 1.27 1.27)) (justify left))
  )
  (hierarchical_label "MIO[52..63]" (shape input) (at 198.12 109.22 0) (fields_autoplaced)
    (effects (font (size 1.27 1.27)) (justify left))
  )
  (hierarchical_label "MIO37" (shape input) (at 91.44 99.06 0) (fields_autoplaced)
    (effects (font (size 1.27 1.27)) (justify left))
  )
  (hierarchical_label "HDA01" (shape input) (at 187.96 66.04 0) (fields_autoplaced)
    (effects (font (size 1.27 1.27)) (justify left))
  )
  (hierarchical_label "GTR_DP3_C2M_P" (shape input) (at 187.96 147.32 0) (fields_autoplaced)
    (effects (font (size 1.27 1.27)) (justify left))
  )
  (hierarchical_label "MIO[64..77]" (shape input) (at 30.48 124.46 180) (fields_autoplaced)
    (effects (font (size 1.27 1.27)) (justify right))
  )
  (hierarchical_label "HPA08_N" (shape input) (at 136.525 48.26 180) (fields_autoplaced)
    (effects (font (size 1.27 1.27)) (justify right))
  )
  (hierarchical_label "MIO41" (shape input) (at 40.64 109.22 180) (fields_autoplaced)
    (effects (font (size 1.27 1.27)) (justify right))
  )
  (hierarchical_label "HPA04_N" (shape input) (at 94.488 35.56 0) (fields_autoplaced)
    (effects (font (size 1.27 1.27)) (justify left))
  )
  (hierarchical_label "JTAG_TDO_M2C" (shape input) (at 40.64 81.28 180) (fields_autoplaced)
    (effects (font (size 1.27 1.27)) (justify right))
  )
  (hierarchical_label "MIO[52..63]" (shape input) (at 125.73 114.3 180) (fields_autoplaced)
    (effects (font (size 1.27 1.27)) (justify right))
  )
  (hierarchical_label "HDA09" (shape input) (at 40.64 60.96 180) (fields_autoplaced)
    (effects (font (size 1.27 1.27)) (justify right))
  )
  (hierarchical_label "GTR_DP1_M2C_P" (shape input) (at 40.64 142.24 180) (fields_autoplaced)
    (effects (font (size 1.27 1.27)) (justify right))
  )
  (hierarchical_label "HDA00_C" (shape input) (at 187.96 63.5 0) (fields_autoplaced)
    (effects (font (size 1.27 1.27)) (justify left))
  )
  (hierarchical_label "JTAG_TCK_C2M" (shape input) (at 40.64 86.36 180) (fields_autoplaced)
    (effects (font (size 1.27 1.27)) (justify right))
  )
  (hierarchical_label "MIO[27..30]" (shape input) (at 198.12 91.44 0) (fields_autoplaced)
    (effects (font (size 1.27 1.27)) (justify left))
  )
  (hierarchical_label "MIO38" (shape input) (at 91.44 104.14 0) (fields_autoplaced)
    (effects (font (size 1.27 1.27)) (justify left))
  )
  (hierarchical_label "MIO[52..63]" (shape input) (at 101.6 119.38 0) (fields_autoplaced)
    (effects (font (size 1.27 1.27)) (justify left))
  )
  (hierarchical_label "MIO25_I2C_SDA" (shape input) (at 137.16 91.44 180) (fields_autoplaced)
    (effects (font (size 1.27 1.27)) (justify right))
  )
  (hierarchical_label "GTR_REFCLK1_C2M_P" (shape input) (at 91.44 147.32 0) (fields_autoplaced)
    (effects (font (size 1.27 1.27)) (justify left))
  )
  (hierarchical_label "HDA02" (shape input) (at 187.96 68.58 0) (fields_autoplaced)
    (effects (font (size 1.27 1.27)) (justify left))
  )
  (hierarchical_label "MIO43" (shape input) (at 40.64 114.3 180) (fields_autoplaced)
    (effects (font (size 1.27 1.27)) (justify right))
  )
  (hierarchical_label "HPA08_P" (shape input) (at 136.525 45.72 180) (fields_autoplaced)
    (effects (font (size 1.27 1.27)) (justify right))
  )
  (hierarchical_label "GTR_REFCLK0_C2M_N" (shape input) (at 137.16 144.78 180) (fields_autoplaced)
    (effects (font (size 1.27 1.27)) (justify right))
  )
  (hierarchical_label "MIO44" (shape input) (at 186.69 104.14 0) (fields_autoplaced)
    (effects (font (size 1.27 1.27)) (justify left))
  )
  (hierarchical_label "HPA00_CC_P" (shape input) (at 134.874 30.48 180) (fields_autoplaced)
    (effects (font (size 1.27 1.27)) (justify right))
  )

  (symbol (lib_id "kria-k26-devboard:GND") (at 146.05 176.53 0) (unit 1)
    (in_bom yes) (on_board yes) (dnp no)
    (property "Reference" "#PWR0187" (at 146.05 182.88 0)
      (effects (font (size 1.27 1.27)) hide)
    )
    (property "Value" "GND" (at 146.05 180.34 0)
      (effects (font (size 1.27 1.27)))
    )
    (property "Footprint" "" (at 154.94 184.15 0)
      (effects (font (size 1.27 1.27) (thickness 0.15)) (justify left bottom) hide)
    )
    (property "Datasheet" "" (at 154.94 189.23 0)
      (effects (font (size 1.27 1.27) (thickness 0.15)) (justify left bottom) hide)
    )
    (property "Author" "Antmicro" (at 154.94 184.15 0)
      (effects (font (size 1.27 1.27) (thickness 0.15)) (justify left bottom) hide)
    )
    (property "License" "Apache-2.0" (at 154.94 186.69 0)
      (effects (font (size 1.27 1.27) (thickness 0.15)) (justify left bottom) hide)
    )
    (pin "1")
    (instances
      (project "kria-k26-devboard"
        (path ""
          (reference "#PWR0187") (unit 1)
        )
      )
    )
  )

  (symbol (lib_id "kria-k26-devboard:C_47u_0805") (at 247.65 198.12 270) (unit 1)
    (in_bom yes) (on_board yes) (dnp no)
    (property "Reference" "C115" (at 248.285 198.755 90)
      (effects (font (size 1.524 1.524)) (justify left))
    )
    (property "Value" "C_47u_0805" (at 243.84 198.12 0)
      (effects (font (size 1.27 1.27) (thickness 0.15)) (justify left bottom) hide)
    )
    (property "Footprint" "kria-k26-devboard-footprints:C_0805_2012Metric" (at 252.73 203.2 0)
      (effects (font (size 1.27 1.27) (thickness 0.15)) (justify left bottom) hide)
    )
    (property "Datasheet" " " (at 247.65 198.12 0)
      (effects (font (size 1.27 1.27) (thickness 0.15)) (justify left bottom) hide)
    )
    (property "Manufacturer" "KEMET" (at 257.81 203.2 0)
      (effects (font (size 1.27 1.27) (thickness 0.15)) (justify left bottom) hide)
    )
    (property "MPN" "C0805C476M9PACTU" (at 255.27 203.2 0)
      (effects (font (size 1.27 1.27) (thickness 0.15)) (justify left bottom) hide)
    )
    (property "Val" "47u" (at 248.285 202.565 90)
      (effects (font (size 1.27 1.27) (thickness 0.15)) (justify left))
    )
    (property "License" "Apache-2.0" (at 224.79 218.44 0)
      (effects (font (size 1.27 1.27) (thickness 0.15)) (justify left bottom) hide)
    )
    (property "Author" "Antmicro" (at 222.25 218.44 0)
      (effects (font (size 1.27 1.27) (thickness 0.15)) (justify left bottom) hide)
    )
    (property "Voltage" "" (at 219.71 218.44 0)
      (effects (font (size 1.27 1.27)) (justify left bottom) hide)
    )
    (property "Dielectric" "" (at 217.17 218.44 0)
      (effects (font (size 1.27 1.27)) (justify left bottom) hide)
    )
    (pin "1")
    (pin "2")
    (instances
      (project "kria-k26-devboard"
        (path ""
          (reference "C115") (unit 1)
        )
      )
    )
  )

  (symbol (lib_id "kria-k26-devboard:C_47u_0805") (at 257.81 198.12 270) (unit 1)
    (in_bom yes) (on_board yes) (dnp no)
    (property "Reference" "C116" (at 258.445 198.755 90)
      (effects (font (size 1.524 1.524)) (justify left))
    )
    (property "Value" "C_47u_0805" (at 254 198.12 0)
      (effects (font (size 1.27 1.27) (thickness 0.15)) (justify left bottom) hide)
    )
    (property "Footprint" "kria-k26-devboard-footprints:C_0805_2012Metric" (at 262.89 203.2 0)
      (effects (font (size 1.27 1.27) (thickness 0.15)) (justify left bottom) hide)
    )
    (property "Datasheet" " " (at 257.81 198.12 0)
      (effects (font (size 1.27 1.27) (thickness 0.15)) (justify left bottom) hide)
    )
    (property "Manufacturer" "KEMET" (at 267.97 203.2 0)
      (effects (font (size 1.27 1.27) (thickness 0.15)) (justify left bottom) hide)
    )
    (property "MPN" "C0805C476M9PACTU" (at 265.43 203.2 0)
      (effects (font (size 1.27 1.27) (thickness 0.15)) (justify left bottom) hide)
    )
    (property "Val" "47u" (at 258.445 202.565 90)
      (effects (font (size 1.27 1.27) (thickness 0.15)) (justify left))
    )
    (property "License" "Apache-2.0" (at 234.95 218.44 0)
      (effects (font (size 1.27 1.27) (thickness 0.15)) (justify left bottom) hide)
    )
    (property "Author" "Antmicro" (at 232.41 218.44 0)
      (effects (font (size 1.27 1.27) (thickness 0.15)) (justify left bottom) hide)
    )
    (property "Voltage" "" (at 229.87 218.44 0)
      (effects (font (size 1.27 1.27)) (justify left bottom) hide)
    )
    (property "Dielectric" "" (at 227.33 218.44 0)
      (effects (font (size 1.27 1.27)) (justify left bottom) hide)
    )
    (pin "1")
    (pin "2")
    (instances
      (project "kria-k26-devboard"
        (path ""
          (reference "C116") (unit 1)
        )
      )
    )
  )

  (symbol (lib_id "kria-k26-devboard:C_1u_0402") (at 267.97 198.12 270) (unit 1)
    (in_bom yes) (on_board yes) (dnp no)
    (property "Reference" "C117" (at 268.605 198.755 90)
      (effects (font (size 1.524 1.524)) (justify left))
    )
    (property "Value" "C_1u_0402" (at 264.16 198.12 0)
      (effects (font (size 1.27 1.27) (thickness 0.15)) (justify left bottom) hide)
    )
    (property "Footprint" "kria-k26-devboard-footprints:C_0402_1005Metric" (at 273.05 203.2 0)
      (effects (font (size 1.27 1.27) (thickness 0.15)) (justify left bottom) hide)
    )
    (property "Datasheet" " " (at 267.97 198.12 0)
      (effects (font (size 1.27 1.27) (thickness 0.15)) (justify left bottom) hide)
    )
    (property "Manufacturer" "TDK" (at 278.13 203.2 0)
      (effects (font (size 1.27 1.27) (thickness 0.15)) (justify left bottom) hide)
    )
    (property "MPN" "C1005X6S1A105K050BC" (at 275.59 203.2 0)
      (effects (font (size 1.27 1.27) (thickness 0.15)) (justify left bottom) hide)
    )
    (property "Val" "1u" (at 268.605 202.565 90)
      (effects (font (size 1.27 1.27) (thickness 0.15)) (justify left))
    )
    (property "License" "Apache-2.0" (at 245.11 218.44 0)
      (effects (font (size 1.27 1.27) (thickness 0.15)) (justify left bottom) hide)
    )
    (property "Author" "Antmicro" (at 242.57 218.44 0)
      (effects (font (size 1.27 1.27) (thickness 0.15)) (justify left bottom) hide)
    )
    (property "Voltage" "" (at 240.03 218.44 0)
      (effects (font (size 1.27 1.27)) (justify left bottom) hide)
    )
    (property "Dielectric" "" (at 237.49 218.44 0)
      (effects (font (size 1.27 1.27)) (justify left bottom) hide)
    )
    (pin "1")
    (pin "2")
    (instances
      (project "kria-k26-devboard"
        (path ""
          (reference "C117") (unit 1)
        )
      )
    )
  )

  (symbol (lib_id "kria-k26-devboard:C_100n_0402") (at 278.13 198.12 270) (unit 1)
    (in_bom yes) (on_board yes) (dnp no)
    (property "Reference" "C118" (at 278.765 198.755 90)
      (effects (font (size 1.524 1.524)) (justify left))
    )
    (property "Value" "C_100n_0402" (at 274.32 198.12 0)
      (effects (font (size 1.27 1.27) (thickness 0.15)) (justify left bottom) hide)
    )
    (property "Footprint" "kria-k26-devboard-footprints:C_0402_1005Metric" (at 283.21 203.2 0)
      (effects (font (size 1.27 1.27) (thickness 0.15)) (justify left bottom) hide)
    )
    (property "Datasheet" "https://search.murata.co.jp/Ceramy/image/img/A01X/G101/ENG/GRM155R61H104KE14-01.pdf" (at 278.13 198.12 0)
      (effects (font (size 1.27 1.27) (thickness 0.15)) (justify left bottom) hide)
    )
    (property "Manufacturer" "Murata" (at 288.29 203.2 0)
      (effects (font (size 1.27 1.27) (thickness 0.15)) (justify left bottom) hide)
    )
    (property "MPN" "GRM155R61H104KE14D" (at 285.75 203.2 0)
      (effects (font (size 1.27 1.27) (thickness 0.15)) (justify left bottom) hide)
    )
    (property "Val" "100n" (at 278.765 202.565 90)
      (effects (font (size 1.27 1.27) (thickness 0.15)) (justify left))
    )
    (property "License" "Apache-2.0" (at 255.27 218.44 0)
      (effects (font (size 1.27 1.27) (thickness 0.15)) (justify left bottom) hide)
    )
    (property "Author" "Antmicro" (at 252.73 218.44 0)
      (effects (font (size 1.27 1.27) (thickness 0.15)) (justify left bottom) hide)
    )
    (property "Voltage" "50V" (at 250.19 218.44 0)
      (effects (font (size 1.27 1.27)) (justify left bottom) hide)
    )
    (property "Dielectric" "X5R" (at 247.65 218.44 0)
      (effects (font (size 1.27 1.27)) (justify left bottom) hide)
    )
    (pin "1")
    (pin "2")
    (instances
      (project "kria-k26-devboard"
        (path ""
          (reference "C118") (unit 1)
        )
      )
    )
  )

  (symbol (lib_id "kria-k26-devboard:GND") (at 50.165 176.53 0) (unit 1)
    (in_bom yes) (on_board yes) (dnp no)
    (property "Reference" "#PWR0144" (at 50.165 182.88 0)
      (effects (font (size 1.27 1.27)) hide)
    )
    (property "Value" "GND" (at 52.07 180.34 0)
      (effects (font (size 1.27 1.27)) (justify right))
    )
    (property "Footprint" "" (at 59.055 184.15 0)
      (effects (font (size 1.27 1.27) (thickness 0.15)) (justify left bottom) hide)
    )
    (property "Datasheet" "" (at 59.055 189.23 0)
      (effects (font (size 1.27 1.27) (thickness 0.15)) (justify left bottom) hide)
    )
    (property "Author" "Antmicro" (at 59.055 184.15 0)
      (effects (font (size 1.27 1.27) (thickness 0.15)) (justify left bottom) hide)
    )
    (property "License" "Apache-2.0" (at 59.055 186.69 0)
      (effects (font (size 1.27 1.27) (thickness 0.15)) (justify left bottom) hide)
    )
    (pin "1")
    (instances
      (project "kria-k26-devboard"
        (path ""
          (reference "#PWR0144") (unit 1)
        )
      )
    )
  )

  (symbol (lib_id "kria-k26-devboard:Plug_Samtec_ADM6_4x60_ADM6-60-01.5-L-4-2-A-TR") (at 344.17 25.4 0) (unit 2)
    (in_bom no) (on_board yes) (dnp yes) (fields_autoplaced)
    (property "Reference" "J_SOM240_2" (at 358.14 15.24 0)
      (effects (font (size 1.27 1.27)))
    )
    (property "Value" "ADM6-60-01.5-L-4-2-A-TR" (at 358.14 17.78 0)
      (effects (font (size 1.27 1.27) (thickness 0.15)))
    )
    (property "Footprint" "kria-k26-devboard-footprints:Conn_Plug_Samtec_ADM6_4x60_ADM6-60-01.5-L-4-2-A-TR" (at 344.17 25.4 0)
      (effects (font (size 1.27 1.27) (thickness 0.15)) (justify left bottom) hide)
    )
    (property "Datasheet" "https://suddendocs.samtec.com/catalog_english/adm6.pdf?_gl=1*bo1jwj*_ga*MTc4NzA2NDkyLjE2NjQ4NzY0OTY.*_ga_3KFNZC07WW*MTY3ODg4NTY3MS4xMC4wLjE2Nzg4ODU2NzEuNjAuMC4w" (at 344.17 25.4 0)
      (effects (font (size 1.27 1.27) (thickness 0.15)) (justify left bottom) hide)
    )
    (property "Manufacturer" "Samtec" (at 344.17 25.4 0)
      (effects (font (size 1.27 1.27) (thickness 0.15)) (justify left bottom) hide)
    )
    (property "MPN" "ADM6-60-01.5-L-4-2-A-TR" (at 344.17 25.4 0)
      (effects (font (size 1.27 1.27) (thickness 0.15)) (justify left bottom) hide)
    )
    (property "DNP" "DNP" (at 358.14 20.32 0)
      (effects (font (size 1.27 1.27)))
    )
    (property "Author" "Antmicro" (at 387.35 43.18 0)
      (effects (font (size 1.27 1.27) (thickness 0.15)) (justify left bottom) hide)
    )
    (property "License" "Apache-2.0" (at 387.35 45.72 0)
      (effects (font (size 1.27 1.27) (thickness 0.15)) (justify left bottom) hide)
    )
    (pin "C01")
    (pin "C02")
    (pin "C03")
    (pin "C04")
    (pin "C05")
    (pin "C06")
    (pin "C07")
    (pin "C08")
    (pin "C09")
    (pin "C10")
    (pin "C11")
    (pin "C12")
    (pin "C13")
    (pin "C14")
    (pin "C15")
    (pin "C16")
    (pin "C17")
    (pin "C18")
    (pin "C19")
    (pin "C20")
    (pin "C21")
    (pin "C22")
    (pin "C23")
    (pin "C24")
    (pin "C25")
    (pin "C26")
    (pin "C27")
    (pin "C28")
    (pin "C29")
    (pin "C30")
    (pin "C31")
    (pin "C32")
    (pin "C33")
    (pin "C34")
    (pin "C35")
    (pin "C36")
    (pin "C37")
    (pin "C38")
    (pin "C39")
    (pin "C40")
    (pin "C41")
    (pin "C42")
    (pin "C43")
    (pin "C44")
    (pin "C45")
    (pin "C46")
    (pin "C47")
    (pin "C48")
    (pin "C49")
    (pin "C50")
    (pin "C51")
    (pin "C52")
    (pin "C53")
    (pin "C54")
    (pin "C55")
    (pin "C56")
    (pin "C57")
    (pin "C58")
    (pin "C59")
    (pin "C60")
    (pin "D01")
    (pin "D02")
    (pin "D03")
    (pin "D04")
    (pin "D05")
    (pin "D06")
    (pin "D07")
    (pin "D08")
    (pin "D09")
    (pin "D10")
    (pin "D11")
    (pin "D12")
    (pin "D13")
    (pin "D14")
    (pin "D15")
    (pin "D16")
    (pin "D17")
    (pin "D18")
    (pin "D19")
    (pin "D20")
    (pin "D21")
    (pin "D22")
    (pin "D23")
    (pin "D24")
    (pin "D25")
    (pin "D26")
    (pin "D27")
    (pin "D28")
    (pin "D29")
    (pin "D30")
    (pin "D31")
    (pin "D32")
    (pin "D33")
    (pin "D34")
    (pin "D35")
    (pin "D36")
    (pin "D37")
    (pin "D38")
    (pin "D39")
    (pin "D40")
    (pin "D41")
    (pin "D42")
    (pin "D43")
    (pin "D44")
    (pin "D45")
    (pin "D46")
    (pin "D47")
    (pin "D48")
    (pin "D49")
    (pin "D50")
    (pin "D51")
    (pin "D52")
    (pin "D53")
    (pin "D54")
    (pin "D55")
    (pin "D56")
    (pin "D57")
    (pin "D58")
    (pin "D59")
    (pin "D60")
    (pin "A01")
    (pin "A02")
    (pin "A03")
    (pin "A04")
    (pin "A05")
    (pin "A06")
    (pin "A07")
    (pin "A08")
    (pin "A09")
    (pin "A10")
    (pin "A11")
    (pin "A12")
    (pin "A13")
    (pin "A14")
    (pin "A15")
    (pin "A16")
    (pin "A17")
    (pin "A18")
    (pin "A19")
    (pin "A20")
    (pin "A21")
    (pin "A22")
    (pin "A23")
    (pin "A24")
    (pin "A25")
    (pin "A26")
    (pin "A27")
    (pin "A28")
    (pin "A29")
    (pin "A30")
    (pin "A31")
    (pin "A32")
    (pin "A33")
    (pin "A34")
    (pin "A35")
    (pin "A36")
    (pin "A37")
    (pin "A38")
    (pin "A39")
    (pin "A40")
    (pin "A41")
    (pin "A42")
    (pin "A43")
    (pin "A44")
    (pin "A45")
    (pin "A46")
    (pin "A47")
    (pin "A48")
    (pin "A49")
    (pin "A50")
    (pin "A51")
    (pin "A52")
    (pin "A53")
    (pin "A54")
    (pin "A55")
    (pin "A56")
    (pin "A57")
    (pin "A58")
    (pin "A59")
    (pin "A60")
    (pin "B01")
    (pin "B02")
    (pin "B03")
    (pin "B04")
    (pin "B05")
    (pin "B06")
    (pin "B07")
    (pin "B08")
    (pin "B09")
    (pin "B10")
    (pin "B11")
    (pin "B12")
    (pin "B13")
    (pin "B14")
    (pin "B15")
    (pin "B16")
    (pin "B17")
    (pin "B18")
    (pin "B19")
    (pin "B20")
    (pin "B21")
    (pin "B22")
    (pin "B23")
    (pin "B24")
    (pin "B25")
    (pin "B26")
    (pin "B27")
    (pin "B28")
    (pin "B29")
    (pin "B30")
    (pin "B31")
    (pin "B32")
    (pin "B33")
    (pin "B34")
    (pin "B35")
    (pin "B36")
    (pin "B37")
    (pin "B38")
    (pin "B39")
    (pin "B40")
    (pin "B41")
    (pin "B42")
    (pin "B43")
    (pin "B44")
    (pin "B45")
    (pin "B46")
    (pin "B47")
    (pin "B48")
    (pin "B49")
    (pin "B50")
    (pin "B51")
    (pin "B52")
    (pin "B53")
    (pin "B54")
    (pin "B55")
    (pin "B56")
    (pin "B57")
    (pin "B58")
    (pin "B59")
    (pin "B60")
    (instances
      (project "kria-k26-devboard"
        (path ""
          (reference "J_SOM240_2") (unit 2)
        )
      )
    )
  )

  (symbol (lib_id "kria-k26-devboard:Plug_Samtec_ADM6_4x60_ADM6-60-01.5-L-4-2-A-TR") (at 247.65 25.4 0) (unit 1)
    (in_bom no) (on_board yes) (dnp yes) (fields_autoplaced)
    (property "Reference" "J_SOM240_2" (at 261.62 15.24 0)
      (effects (font (size 1.27 1.27)))
    )
    (property "Value" "ADM6-60-01.5-L-4-2-A-TR" (at 261.62 17.78 0)
      (effects (font (size 1.27 1.27) (thickness 0.15)))
    )
    (property "Footprint" "kria-k26-devboard-footprints:Conn_Plug_Samtec_ADM6_4x60_ADM6-60-01.5-L-4-2-A-TR" (at 247.65 25.4 0)
      (effects (font (size 1.27 1.27) (thickness 0.15)) (justify left bottom) hide)
    )
    (property "Datasheet" "https://suddendocs.samtec.com/catalog_english/adm6.pdf?_gl=1*bo1jwj*_ga*MTc4NzA2NDkyLjE2NjQ4NzY0OTY.*_ga_3KFNZC07WW*MTY3ODg4NTY3MS4xMC4wLjE2Nzg4ODU2NzEuNjAuMC4w" (at 247.65 25.4 0)
      (effects (font (size 1.27 1.27) (thickness 0.15)) (justify left bottom) hide)
    )
    (property "Manufacturer" "Samtec" (at 247.65 25.4 0)
      (effects (font (size 1.27 1.27) (thickness 0.15)) (justify left bottom) hide)
    )
    (property "MPN" "ADM6-60-01.5-L-4-2-A-TR" (at 247.65 25.4 0)
      (effects (font (size 1.27 1.27) (thickness 0.15)) (justify left bottom) hide)
    )
    (property "DNP" "DNP" (at 261.62 20.32 0)
      (effects (font (size 1.27 1.27)))
    )
    (property "Author" "Antmicro" (at 290.83 43.18 0)
      (effects (font (size 1.27 1.27) (thickness 0.15)) (justify left bottom) hide)
    )
    (property "License" "Apache-2.0" (at 290.83 45.72 0)
      (effects (font (size 1.27 1.27) (thickness 0.15)) (justify left bottom) hide)
    )
    (pin "A01")
    (pin "A02")
    (pin "A03")
    (pin "A04")
    (pin "A05")
    (pin "A06")
    (pin "A07")
    (pin "A08")
    (pin "A09")
    (pin "A10")
    (pin "A11")
    (pin "A12")
    (pin "A13")
    (pin "A14")
    (pin "A15")
    (pin "A16")
    (pin "A17")
    (pin "A18")
    (pin "A19")
    (pin "A20")
    (pin "A21")
    (pin "A22")
    (pin "A23")
    (pin "A24")
    (pin "A25")
    (pin "A26")
    (pin "A27")
    (pin "A28")
    (pin "A29")
    (pin "A30")
    (pin "A31")
    (pin "A32")
    (pin "A33")
    (pin "A34")
    (pin "A35")
    (pin "A36")
    (pin "A37")
    (pin "A38")
    (pin "A39")
    (pin "A40")
    (pin "A41")
    (pin "A42")
    (pin "A43")
    (pin "A44")
    (pin "A45")
    (pin "A46")
    (pin "A47")
    (pin "A48")
    (pin "A49")
    (pin "A50")
    (pin "A51")
    (pin "A52")
    (pin "A53")
    (pin "A54")
    (pin "A55")
    (pin "A56")
    (pin "A57")
    (pin "A58")
    (pin "A59")
    (pin "A60")
    (pin "B01")
    (pin "B02")
    (pin "B03")
    (pin "B04")
    (pin "B05")
    (pin "B06")
    (pin "B07")
    (pin "B08")
    (pin "B09")
    (pin "B10")
    (pin "B11")
    (pin "B12")
    (pin "B13")
    (pin "B14")
    (pin "B15")
    (pin "B16")
    (pin "B17")
    (pin "B18")
    (pin "B19")
    (pin "B20")
    (pin "B21")
    (pin "B22")
    (pin "B23")
    (pin "B24")
    (pin "B25")
    (pin "B26")
    (pin "B27")
    (pin "B28")
    (pin "B29")
    (pin "B30")
    (pin "B31")
    (pin "B32")
    (pin "B33")
    (pin "B34")
    (pin "B35")
    (pin "B36")
    (pin "B37")
    (pin "B38")
    (pin "B39")
    (pin "B40")
    (pin "B41")
    (pin "B42")
    (pin "B43")
    (pin "B44")
    (pin "B45")
    (pin "B46")
    (pin "B47")
    (pin "B48")
    (pin "B49")
    (pin "B50")
    (pin "B51")
    (pin "B52")
    (pin "B53")
    (pin "B54")
    (pin "B55")
    (pin "B56")
    (pin "B57")
    (pin "B58")
    (pin "B59")
    (pin "B60")
    (pin "C01")
    (pin "C02")
    (pin "C03")
    (pin "C04")
    (pin "C05")
    (pin "C06")
    (pin "C07")
    (pin "C08")
    (pin "C09")
    (pin "C10")
    (pin "C11")
    (pin "C12")
    (pin "C13")
    (pin "C14")
    (pin "C15")
    (pin "C16")
    (pin "C17")
    (pin "C18")
    (pin "C19")
    (pin "C20")
    (pin "C21")
    (pin "C22")
    (pin "C23")
    (pin "C24")
    (pin "C25")
    (pin "C26")
    (pin "C27")
    (pin "C28")
    (pin "C29")
    (pin "C30")
    (pin "C31")
    (pin "C32")
    (pin "C33")
    (pin "C34")
    (pin "C35")
    (pin "C36")
    (pin "C37")
    (pin "C38")
    (pin "C39")
    (pin "C40")
    (pin "C41")
    (pin "C42")
    (pin "C43")
    (pin "C44")
    (pin "C45")
    (pin "C46")
    (pin "C47")
    (pin "C48")
    (pin "C49")
    (pin "C50")
    (pin "C51")
    (pin "C52")
    (pin "C53")
    (pin "C54")
    (pin "C55")
    (pin "C56")
    (pin "C57")
    (pin "C58")
    (pin "C59")
    (pin "C60")
    (pin "D01")
    (pin "D02")
    (pin "D03")
    (pin "D04")
    (pin "D05")
    (pin "D06")
    (pin "D07")
    (pin "D08")
    (pin "D09")
    (pin "D10")
    (pin "D11")
    (pin "D12")
    (pin "D13")
    (pin "D14")
    (pin "D15")
    (pin "D16")
    (pin "D17")
    (pin "D18")
    (pin "D19")
    (pin "D20")
    (pin "D21")
    (pin "D22")
    (pin "D23")
    (pin "D24")
    (pin "D25")
    (pin "D26")
    (pin "D27")
    (pin "D28")
    (pin "D29")
    (pin "D30")
    (pin "D31")
    (pin "D32")
    (pin "D33")
    (pin "D34")
    (pin "D35")
    (pin "D36")
    (pin "D37")
    (pin "D38")
    (pin "D39")
    (pin "D40")
    (pin "D41")
    (pin "D42")
    (pin "D43")
    (pin "D44")
    (pin "D45")
    (pin "D46")
    (pin "D47")
    (pin "D48")
    (pin "D49")
    (pin "D50")
    (pin "D51")
    (pin "D52")
    (pin "D53")
    (pin "D54")
    (pin "D55")
    (pin "D56")
    (pin "D57")
    (pin "D58")
    (pin "D59")
    (pin "D60")
    (instances
      (project "kria-k26-devboard"
        (path ""
          (reference "J_SOM240_2") (unit 1)
        )
      )
    )
  )

  (symbol (lib_id "kria-k26-devboard:Plug_Samtec_ADM6_4x60_ADM6-60-01.5-L-4-2-A-TR") (at 148.59 25.4 0) (unit 2)
    (in_bom yes) (on_board yes) (dnp no) (fields_autoplaced)
    (property "Reference" "J_SOM240_1" (at 162.56 17.78 0)
      (effects (font (size 1.27 1.27)))
    )
    (property "Value" "ADM6-60-01.5-L-4-2-A-TR" (at 162.56 20.32 0)
      (effects (font (size 1.27 1.27) (thickness 0.15)))
    )
    (property "Footprint" "kria-k26-devboard-footprints:Conn_Plug_Samtec_ADM6_4x60_ADM6-60-01.5-L-4-2-A-TR" (at 148.59 25.4 0)
      (effects (font (size 1.27 1.27) (thickness 0.15)) (justify left bottom) hide)
    )
    (property "Datasheet" "https://suddendocs.samtec.com/catalog_english/adm6.pdf?_gl=1*bo1jwj*_ga*MTc4NzA2NDkyLjE2NjQ4NzY0OTY.*_ga_3KFNZC07WW*MTY3ODg4NTY3MS4xMC4wLjE2Nzg4ODU2NzEuNjAuMC4w" (at 148.59 25.4 0)
      (effects (font (size 1.27 1.27) (thickness 0.15)) (justify left bottom) hide)
    )
    (property "Manufacturer" "Samtec" (at 148.59 25.4 0)
      (effects (font (size 1.27 1.27) (thickness 0.15)) (justify left bottom) hide)
    )
    (property "MPN" "ADM6-60-01.5-L-4-2-A-TR" (at 148.59 25.4 0)
      (effects (font (size 1.27 1.27) (thickness 0.15)) (justify left bottom) hide)
    )
    (property "Author" "Antmicro" (at 191.77 43.18 0)
      (effects (font (size 1.27 1.27) (thickness 0.15)) (justify left bottom) hide)
    )
    (property "License" "Apache-2.0" (at 191.77 45.72 0)
      (effects (font (size 1.27 1.27) (thickness 0.15)) (justify left bottom) hide)
    )
    (pin "C01")
    (pin "C02")
    (pin "C03")
    (pin "C04")
    (pin "C05")
    (pin "C06")
    (pin "C07")
    (pin "C08")
    (pin "C09")
    (pin "C10")
    (pin "C11")
    (pin "C12")
    (pin "C13")
    (pin "C14")
    (pin "C15")
    (pin "C16")
    (pin "C17")
    (pin "C18")
    (pin "C19")
    (pin "C20")
    (pin "C21")
    (pin "C22")
    (pin "C23")
    (pin "C24")
    (pin "C25")
    (pin "C26")
    (pin "C27")
    (pin "C28")
    (pin "C29")
    (pin "C30")
    (pin "C31")
    (pin "C32")
    (pin "C33")
    (pin "C34")
    (pin "C35")
    (pin "C36")
    (pin "C37")
    (pin "C38")
    (pin "C39")
    (pin "C40")
    (pin "C41")
    (pin "C42")
    (pin "C43")
    (pin "C44")
    (pin "C45")
    (pin "C46")
    (pin "C47")
    (pin "C48")
    (pin "C49")
    (pin "C50")
    (pin "C51")
    (pin "C52")
    (pin "C53")
    (pin "C54")
    (pin "C55")
    (pin "C56")
    (pin "C57")
    (pin "C58")
    (pin "C59")
    (pin "C60")
    (pin "D01")
    (pin "D02")
    (pin "D03")
    (pin "D04")
    (pin "D05")
    (pin "D06")
    (pin "D07")
    (pin "D08")
    (pin "D09")
    (pin "D10")
    (pin "D11")
    (pin "D12")
    (pin "D13")
    (pin "D14")
    (pin "D15")
    (pin "D16")
    (pin "D17")
    (pin "D18")
    (pin "D19")
    (pin "D20")
    (pin "D21")
    (pin "D22")
    (pin "D23")
    (pin "D24")
    (pin "D25")
    (pin "D26")
    (pin "D27")
    (pin "D28")
    (pin "D29")
    (pin "D30")
    (pin "D31")
    (pin "D32")
    (pin "D33")
    (pin "D34")
    (pin "D35")
    (pin "D36")
    (pin "D37")
    (pin "D38")
    (pin "D39")
    (pin "D40")
    (pin "D41")
    (pin "D42")
    (pin "D43")
    (pin "D44")
    (pin "D45")
    (pin "D46")
    (pin "D47")
    (pin "D48")
    (pin "D49")
    (pin "D50")
    (pin "D51")
    (pin "D52")
    (pin "D53")
    (pin "D54")
    (pin "D55")
    (pin "D56")
    (pin "D57")
    (pin "D58")
    (pin "D59")
    (pin "D60")
    (pin "A01")
    (pin "A02")
    (pin "A03")
    (pin "A04")
    (pin "A05")
    (pin "A06")
    (pin "A07")
    (pin "A08")
    (pin "A09")
    (pin "A10")
    (pin "A11")
    (pin "A12")
    (pin "A13")
    (pin "A14")
    (pin "A15")
    (pin "A16")
    (pin "A17")
    (pin "A18")
    (pin "A19")
    (pin "A20")
    (pin "A21")
    (pin "A22")
    (pin "A23")
    (pin "A24")
    (pin "A25")
    (pin "A26")
    (pin "A27")
    (pin "A28")
    (pin "A29")
    (pin "A30")
    (pin "A31")
    (pin "A32")
    (pin "A33")
    (pin "A34")
    (pin "A35")
    (pin "A36")
    (pin "A37")
    (pin "A38")
    (pin "A39")
    (pin "A40")
    (pin "A41")
    (pin "A42")
    (pin "A43")
    (pin "A44")
    (pin "A45")
    (pin "A46")
    (pin "A47")
    (pin "A48")
    (pin "A49")
    (pin "A50")
    (pin "A51")
    (pin "A52")
    (pin "A53")
    (pin "A54")
    (pin "A55")
    (pin "A56")
    (pin "A57")
    (pin "A58")
    (pin "A59")
    (pin "A60")
    (pin "B01")
    (pin "B02")
    (pin "B03")
    (pin "B04")
    (pin "B05")
    (pin "B06")
    (pin "B07")
    (pin "B08")
    (pin "B09")
    (pin "B10")
    (pin "B11")
    (pin "B12")
    (pin "B13")
    (pin "B14")
    (pin "B15")
    (pin "B16")
    (pin "B17")
    (pin "B18")
    (pin "B19")
    (pin "B20")
    (pin "B21")
    (pin "B22")
    (pin "B23")
    (pin "B24")
    (pin "B25")
    (pin "B26")
    (pin "B27")
    (pin "B28")
    (pin "B29")
    (pin "B30")
    (pin "B31")
    (pin "B32")
    (pin "B33")
    (pin "B34")
    (pin "B35")
    (pin "B36")
    (pin "B37")
    (pin "B38")
    (pin "B39")
    (pin "B40")
    (pin "B41")
    (pin "B42")
    (pin "B43")
    (pin "B44")
    (pin "B45")
    (pin "B46")
    (pin "B47")
    (pin "B48")
    (pin "B49")
    (pin "B50")
    (pin "B51")
    (pin "B52")
    (pin "B53")
    (pin "B54")
    (pin "B55")
    (pin "B56")
    (pin "B57")
    (pin "B58")
    (pin "B59")
    (pin "B60")
    (instances
      (project "kria-k26-devboard"
        (path ""
          (reference "J_SOM240_1") (unit 2)
        )
      )
    )
  )

  (symbol (lib_id "kria-k26-devboard:Plug_Samtec_ADM6_4x60_ADM6-60-01.5-L-4-2-A-TR") (at 52.07 25.4 0) (unit 1)
    (in_bom yes) (on_board yes) (dnp no) (fields_autoplaced)
    (property "Reference" "J_SOM240_1" (at 66.04 17.78 0)
      (effects (font (size 1.27 1.27)))
    )
    (property "Value" "ADM6-60-01.5-L-4-2-A-TR" (at 66.04 20.32 0)
      (effects (font (size 1.27 1.27) (thickness 0.15)))
    )
    (property "Footprint" "kria-k26-devboard-footprints:Conn_Plug_Samtec_ADM6_4x60_ADM6-60-01.5-L-4-2-A-TR" (at 52.07 25.4 0)
      (effects (font (size 1.27 1.27) (thickness 0.15)) (justify left bottom) hide)
    )
    (property "Datasheet" "https://suddendocs.samtec.com/catalog_english/adm6.pdf?_gl=1*bo1jwj*_ga*MTc4NzA2NDkyLjE2NjQ4NzY0OTY.*_ga_3KFNZC07WW*MTY3ODg4NTY3MS4xMC4wLjE2Nzg4ODU2NzEuNjAuMC4w" (at 52.07 25.4 0)
      (effects (font (size 1.27 1.27) (thickness 0.15)) (justify left bottom) hide)
    )
    (property "Manufacturer" "Samtec" (at 52.07 25.4 0)
      (effects (font (size 1.27 1.27) (thickness 0.15)) (justify left bottom) hide)
    )
    (property "MPN" "ADM6-60-01.5-L-4-2-A-TR" (at 52.07 25.4 0)
      (effects (font (size 1.27 1.27) (thickness 0.15)) (justify left bottom) hide)
    )
    (property "Author" "Antmicro" (at 95.25 43.18 0)
      (effects (font (size 1.27 1.27) (thickness 0.15)) (justify left bottom) hide)
    )
    (property "License" "Apache-2.0" (at 95.25 45.72 0)
      (effects (font (size 1.27 1.27) (thickness 0.15)) (justify left bottom) hide)
    )
    (pin "A01")
    (pin "A02")
    (pin "A03")
    (pin "A04")
    (pin "A05")
    (pin "A06")
    (pin "A07")
    (pin "A08")
    (pin "A09")
    (pin "A10")
    (pin "A11")
    (pin "A12")
    (pin "A13")
    (pin "A14")
    (pin "A15")
    (pin "A16")
    (pin "A17")
    (pin "A18")
    (pin "A19")
    (pin "A20")
    (pin "A21")
    (pin "A22")
    (pin "A23")
    (pin "A24")
    (pin "A25")
    (pin "A26")
    (pin "A27")
    (pin "A28")
    (pin "A29")
    (pin "A30")
    (pin "A31")
    (pin "A32")
    (pin "A33")
    (pin "A34")
    (pin "A35")
    (pin "A36")
    (pin "A37")
    (pin "A38")
    (pin "A39")
    (pin "A40")
    (pin "A41")
    (pin "A42")
    (pin "A43")
    (pin "A44")
    (pin "A45")
    (pin "A46")
    (pin "A47")
    (pin "A48")
    (pin "A49")
    (pin "A50")
    (pin "A51")
    (pin "A52")
    (pin "A53")
    (pin "A54")
    (pin "A55")
    (pin "A56")
    (pin "A57")
    (pin "A58")
    (pin "A59")
    (pin "A60")
    (pin "B01")
    (pin "B02")
    (pin "B03")
    (pin "B04")
    (pin "B05")
    (pin "B06")
    (pin "B07")
    (pin "B08")
    (pin "B09")
    (pin "B10")
    (pin "B11")
    (pin "B12")
    (pin "B13")
    (pin "B14")
    (pin "B15")
    (pin "B16")
    (pin "B17")
    (pin "B18")
    (pin "B19")
    (pin "B20")
    (pin "B21")
    (pin "B22")
    (pin "B23")
    (pin "B24")
    (pin "B25")
    (pin "B26")
    (pin "B27")
    (pin "B28")
    (pin "B29")
    (pin "B30")
    (pin "B31")
    (pin "B32")
    (pin "B33")
    (pin "B34")
    (pin "B35")
    (pin "B36")
    (pin "B37")
    (pin "B38")
    (pin "B39")
    (pin "B40")
    (pin "B41")
    (pin "B42")
    (pin "B43")
    (pin "B44")
    (pin "B45")
    (pin "B46")
    (pin "B47")
    (pin "B48")
    (pin "B49")
    (pin "B50")
    (pin "B51")
    (pin "B52")
    (pin "B53")
    (pin "B54")
    (pin "B55")
    (pin "B56")
    (pin "B57")
    (pin "B58")
    (pin "B59")
    (pin "B60")
    (pin "C01")
    (pin "C02")
    (pin "C03")
    (pin "C04")
    (pin "C05")
    (pin "C06")
    (pin "C07")
    (pin "C08")
    (pin "C09")
    (pin "C10")
    (pin "C11")
    (pin "C12")
    (pin "C13")
    (pin "C14")
    (pin "C15")
    (pin "C16")
    (pin "C17")
    (pin "C18")
    (pin "C19")
    (pin "C20")
    (pin "C21")
    (pin "C22")
    (pin "C23")
    (pin "C24")
    (pin "C25")
    (pin "C26")
    (pin "C27")
    (pin "C28")
    (pin "C29")
    (pin "C30")
    (pin "C31")
    (pin "C32")
    (pin "C33")
    (pin "C34")
    (pin "C35")
    (pin "C36")
    (pin "C37")
    (pin "C38")
    (pin "C39")
    (pin "C40")
    (pin "C41")
    (pin "C42")
    (pin "C43")
    (pin "C44")
    (pin "C45")
    (pin "C46")
    (pin "C47")
    (pin "C48")
    (pin "C49")
    (pin "C50")
    (pin "C51")
    (pin "C52")
    (pin "C53")
    (pin "C54")
    (pin "C55")
    (pin "C56")
    (pin "C57")
    (pin "C58")
    (pin "C59")
    (pin "C60")
    (pin "D01")
    (pin "D02")
    (pin "D03")
    (pin "D04")
    (pin "D05")
    (pin "D06")
    (pin "D07")
    (pin "D08")
    (pin "D09")
    (pin "D10")
    (pin "D11")
    (pin "D12")
    (pin "D13")
    (pin "D14")
    (pin "D15")
    (pin "D16")
    (pin "D17")
    (pin "D18")
    (pin "D19")
    (pin "D20")
    (pin "D21")
    (pin "D22")
    (pin "D23")
    (pin "D24")
    (pin "D25")
    (pin "D26")
    (pin "D27")
    (pin "D28")
    (pin "D29")
    (pin "D30")
    (pin "D31")
    (pin "D32")
    (pin "D33")
    (pin "D34")
    (pin "D35")
    (pin "D36")
    (pin "D37")
    (pin "D38")
    (pin "D39")
    (pin "D40")
    (pin "D41")
    (pin "D42")
    (pin "D43")
    (pin "D44")
    (pin "D45")
    (pin "D46")
    (pin "D47")
    (pin "D48")
    (pin "D49")
    (pin "D50")
    (pin "D51")
    (pin "D52")
    (pin "D53")
    (pin "D54")
    (pin "D55")
    (pin "D56")
    (pin "D57")
    (pin "D58")
    (pin "D59")
    (pin "D60")
    (instances
      (project "kria-k26-devboard"
        (path ""
          (reference "J_SOM240_1") (unit 1)
        )
      )
    )
  )

  (symbol (lib_id "kria-k26-devboard:C_47u_0805") (at 247.65 223.52 270) (unit 1)
    (in_bom yes) (on_board yes) (dnp no)
    (property "Reference" "C119" (at 248.285 224.155 90)
      (effects (font (size 1.524 1.524)) (justify left))
    )
    (property "Value" "C_47u_0805" (at 243.84 223.52 0)
      (effects (font (size 1.27 1.27) (thickness 0.15)) (justify left bottom) hide)
    )
    (property "Footprint" "kria-k26-devboard-footprints:C_0805_2012Metric" (at 252.73 228.6 0)
      (effects (font (size 1.27 1.27) (thickness 0.15)) (justify left bottom) hide)
    )
    (property "Datasheet" " " (at 247.65 223.52 0)
      (effects (font (size 1.27 1.27) (thickness 0.15)) (justify left bottom) hide)
    )
    (property "Manufacturer" "KEMET" (at 257.81 228.6 0)
      (effects (font (size 1.27 1.27) (thickness 0.15)) (justify left bottom) hide)
    )
    (property "MPN" "C0805C476M9PACTU" (at 255.27 228.6 0)
      (effects (font (size 1.27 1.27) (thickness 0.15)) (justify left bottom) hide)
    )
    (property "Val" "47u" (at 248.285 227.965 90)
      (effects (font (size 1.27 1.27) (thickness 0.15)) (justify left))
    )
    (property "License" "Apache-2.0" (at 224.79 243.84 0)
      (effects (font (size 1.27 1.27) (thickness 0.15)) (justify left bottom) hide)
    )
    (property "Author" "Antmicro" (at 222.25 243.84 0)
      (effects (font (size 1.27 1.27) (thickness 0.15)) (justify left bottom) hide)
    )
    (property "Voltage" "" (at 219.71 243.84 0)
      (effects (font (size 1.27 1.27)) (justify left bottom) hide)
    )
    (property "Dielectric" "" (at 217.17 243.84 0)
      (effects (font (size 1.27 1.27)) (justify left bottom) hide)
    )
    (pin "1")
    (pin "2")
    (instances
      (project "kria-k26-devboard"
        (path ""
          (reference "C119") (unit 1)
        )
      )
    )
  )

  (symbol (lib_id "kria-k26-devboard:C_47u_0805") (at 257.81 223.52 270) (unit 1)
    (in_bom yes) (on_board yes) (dnp no)
    (property "Reference" "C120" (at 257.81 224.155 90)
      (effects (font (size 1.524 1.524)) (justify left))
    )
    (property "Value" "C_47u_0805" (at 254 223.52 0)
      (effects (font (size 1.27 1.27) (thickness 0.15)) (justify left bottom) hide)
    )
    (property "Footprint" "kria-k26-devboard-footprints:C_0805_2012Metric" (at 262.89 228.6 0)
      (effects (font (size 1.27 1.27) (thickness 0.15)) (justify left bottom) hide)
    )
    (property "Datasheet" " " (at 257.81 223.52 0)
      (effects (font (size 1.27 1.27) (thickness 0.15)) (justify left bottom) hide)
    )
    (property "Manufacturer" "KEMET" (at 267.97 228.6 0)
      (effects (font (size 1.27 1.27) (thickness 0.15)) (justify left bottom) hide)
    )
    (property "MPN" "C0805C476M9PACTU" (at 265.43 228.6 0)
      (effects (font (size 1.27 1.27) (thickness 0.15)) (justify left bottom) hide)
    )
    (property "Val" "47u" (at 257.81 227.965 90)
      (effects (font (size 1.27 1.27) (thickness 0.15)) (justify left))
    )
    (property "License" "Apache-2.0" (at 234.95 243.84 0)
      (effects (font (size 1.27 1.27) (thickness 0.15)) (justify left bottom) hide)
    )
    (property "Author" "Antmicro" (at 232.41 243.84 0)
      (effects (font (size 1.27 1.27) (thickness 0.15)) (justify left bottom) hide)
    )
    (property "Voltage" "" (at 229.87 243.84 0)
      (effects (font (size 1.27 1.27)) (justify left bottom) hide)
    )
    (property "Dielectric" "" (at 227.33 243.84 0)
      (effects (font (size 1.27 1.27)) (justify left bottom) hide)
    )
    (pin "1")
    (pin "2")
    (instances
      (project "kria-k26-devboard"
        (path ""
          (reference "C120") (unit 1)
        )
      )
    )
  )

  (symbol (lib_id "kria-k26-devboard:C_1u_0402") (at 267.97 223.52 270) (unit 1)
    (in_bom yes) (on_board yes) (dnp no)
    (property "Reference" "C121" (at 267.97 224.155 90)
      (effects (font (size 1.524 1.524)) (justify left))
    )
    (property "Value" "C_1u_0402" (at 264.16 223.52 0)
      (effects (font (size 1.27 1.27) (thickness 0.15)) (justify left bottom) hide)
    )
    (property "Footprint" "kria-k26-devboard-footprints:C_0402_1005Metric" (at 273.05 228.6 0)
      (effects (font (size 1.27 1.27) (thickness 0.15)) (justify left bottom) hide)
    )
    (property "Datasheet" " " (at 267.97 223.52 0)
      (effects (font (size 1.27 1.27) (thickness 0.15)) (justify left bottom) hide)
    )
    (property "Manufacturer" "TDK" (at 278.13 228.6 0)
      (effects (font (size 1.27 1.27) (thickness 0.15)) (justify left bottom) hide)
    )
    (property "MPN" "C1005X6S1A105K050BC" (at 275.59 228.6 0)
      (effects (font (size 1.27 1.27) (thickness 0.15)) (justify left bottom) hide)
    )
    (property "Val" "1u" (at 267.97 227.965 90)
      (effects (font (size 1.27 1.27) (thickness 0.15)) (justify left))
    )
    (property "License" "Apache-2.0" (at 245.11 243.84 0)
      (effects (font (size 1.27 1.27) (thickness 0.15)) (justify left bottom) hide)
    )
    (property "Author" "Antmicro" (at 242.57 243.84 0)
      (effects (font (size 1.27 1.27) (thickness 0.15)) (justify left bottom) hide)
    )
    (property "Voltage" "" (at 240.03 243.84 0)
      (effects (font (size 1.27 1.27)) (justify left bottom) hide)
    )
    (property "Dielectric" "" (at 237.49 243.84 0)
      (effects (font (size 1.27 1.27)) (justify left bottom) hide)
    )
    (pin "1")
    (pin "2")
    (instances
      (project "kria-k26-devboard"
        (path ""
          (reference "C121") (unit 1)
        )
      )
    )
  )

  (symbol (lib_id "kria-k26-devboard:C_100n_0402") (at 278.13 223.52 270) (unit 1)
    (in_bom yes) (on_board yes) (dnp no)
    (property "Reference" "C122" (at 278.765 224.155 90)
      (effects (font (size 1.524 1.524)) (justify left))
    )
    (property "Value" "C_100n_0402" (at 274.32 223.52 0)
      (effects (font (size 1.27 1.27) (thickness 0.15)) (justify left bottom) hide)
    )
    (property "Footprint" "kria-k26-devboard-footprints:C_0402_1005Metric" (at 283.21 228.6 0)
      (effects (font (size 1.27 1.27) (thickness 0.15)) (justify left bottom) hide)
    )
    (property "Datasheet" "https://search.murata.co.jp/Ceramy/image/img/A01X/G101/ENG/GRM155R61H104KE14-01.pdf" (at 278.13 223.52 0)
      (effects (font (size 1.27 1.27) (thickness 0.15)) (justify left bottom) hide)
    )
    (property "Manufacturer" "Murata" (at 288.29 228.6 0)
      (effects (font (size 1.27 1.27) (thickness 0.15)) (justify left bottom) hide)
    )
    (property "MPN" "GRM155R61H104KE14D" (at 285.75 228.6 0)
      (effects (font (size 1.27 1.27) (thickness 0.15)) (justify left bottom) hide)
    )
    (property "Val" "100n" (at 278.765 227.965 90)
      (effects (font (size 1.27 1.27) (thickness 0.15)) (justify left))
    )
    (property "License" "Apache-2.0" (at 255.27 243.84 0)
      (effects (font (size 1.27 1.27) (thickness 0.15)) (justify left bottom) hide)
    )
    (property "Author" "Antmicro" (at 252.73 243.84 0)
      (effects (font (size 1.27 1.27) (thickness 0.15)) (justify left bottom) hide)
    )
    (property "Voltage" "50V" (at 250.19 243.84 0)
      (effects (font (size 1.27 1.27)) (justify left bottom) hide)
    )
    (property "Dielectric" "X5R" (at 247.65 243.84 0)
      (effects (font (size 1.27 1.27)) (justify left bottom) hide)
    )
    (pin "1")
    (pin "2")
    (instances
      (project "kria-k26-devboard"
        (path ""
          (reference "C122") (unit 1)
        )
      )
    )
  )

  (symbol (lib_id "kria-k26-devboard:GND") (at 247.65 228.6 0) (unit 1)
    (in_bom yes) (on_board yes) (dnp no) (fields_autoplaced)
    (property "Reference" "#PWR0165" (at 247.65 234.95 0)
      (effects (font (size 1.27 1.27)) hide)
    )
    (property "Value" "GND" (at 247.65 233.68 0)
      (effects (font (size 1.27 1.27)))
    )
    (property "Footprint" "" (at 256.54 236.22 0)
      (effects (font (size 1.27 1.27) (thickness 0.15)) (justify left bottom) hide)
    )
    (property "Datasheet" "" (at 256.54 241.3 0)
      (effects (font (size 1.27 1.27) (thickness 0.15)) (justify left bottom) hide)
    )
    (property "Author" "Antmicro" (at 256.54 236.22 0)
      (effects (font (size 1.27 1.27) (thickness 0.15)) (justify left bottom) hide)
    )
    (property "License" "Apache-2.0" (at 256.54 238.76 0)
      (effects (font (size 1.27 1.27) (thickness 0.15)) (justify left bottom) hide)
    )
    (pin "1")
    (instances
      (project "kria-k26-devboard"
        (path ""
          (reference "#PWR0165") (unit 1)
        )
      )
    )
  )

  (symbol (lib_id "kria-k26-devboard:GND") (at 81.915 176.53 0) (unit 1)
    (in_bom yes) (on_board yes) (dnp no)
    (property "Reference" "#PWR0164" (at 81.915 182.88 0)
      (effects (font (size 1.27 1.27)) hide)
    )
    (property "Value" "GND" (at 80.01 180.34 0)
      (effects (font (size 1.27 1.27)) (justify left))
    )
    (property "Footprint" "" (at 90.805 184.15 0)
      (effects (font (size 1.27 1.27) (thickness 0.15)) (justify left bottom) hide)
    )
    (property "Datasheet" "" (at 90.805 189.23 0)
      (effects (font (size 1.27 1.27) (thickness 0.15)) (justify left bottom) hide)
    )
    (property "Author" "Antmicro" (at 90.805 184.15 0)
      (effects (font (size 1.27 1.27) (thickness 0.15)) (justify left bottom) hide)
    )
    (property "License" "Apache-2.0" (at 90.805 186.69 0)
      (effects (font (size 1.27 1.27) (thickness 0.15)) (justify left bottom) hide)
    )
    (pin "1")
    (instances
      (project "kria-k26-devboard"
        (path ""
          (reference "#PWR0164") (unit 1)
        )
      )
    )
  )

  (symbol (lib_id "kria-k26-devboard:GND") (at 180.34 60.96 90) (unit 1)
    (in_bom yes) (on_board yes) (dnp no) (fields_autoplaced)
    (property "Reference" "#PWR0193" (at 186.69 60.96 0)
      (effects (font (size 1.27 1.27)) hide)
    )
    (property "Value" "GND" (at 184.15 60.9599 90)
      (effects (font (size 1.27 1.27)) (justify right))
    )
    (property "Footprint" "" (at 187.96 52.07 0)
      (effects (font (size 1.27 1.27) (thickness 0.15)) (justify left bottom) hide)
    )
    (property "Datasheet" "" (at 193.04 52.07 0)
      (effects (font (size 1.27 1.27) (thickness 0.15)) (justify left bottom) hide)
    )
    (property "Author" "Antmicro" (at 187.96 52.07 0)
      (effects (font (size 1.27 1.27) (thickness 0.15)) (justify left bottom) hide)
    )
    (property "License" "Apache-2.0" (at 190.5 52.07 0)
      (effects (font (size 1.27 1.27) (thickness 0.15)) (justify left bottom) hide)
    )
    (pin "1")
    (instances
      (project "kria-k26-devboard"
        (path ""
          (reference "#PWR0193") (unit 1)
        )
      )
    )
  )

  (symbol (lib_id "kria-k26-devboard:GND") (at 180.34 53.34 90) (unit 1)
    (in_bom yes) (on_board yes) (dnp no) (fields_autoplaced)
    (property "Reference" "#PWR0192" (at 186.69 53.34 0)
      (effects (font (size 1.27 1.27)) hide)
    )
    (property "Value" "GND" (at 184.15 53.3399 90)
      (effects (font (size 1.27 1.27)) (justify right))
    )
    (property "Footprint" "" (at 187.96 44.45 0)
      (effects (font (size 1.27 1.27) (thickness 0.15)) (justify left bottom) hide)
    )
    (property "Datasheet" "" (at 193.04 44.45 0)
      (effects (font (size 1.27 1.27) (thickness 0.15)) (justify left bottom) hide)
    )
    (property "Author" "Antmicro" (at 187.96 44.45 0)
      (effects (font (size 1.27 1.27) (thickness 0.15)) (justify left bottom) hide)
    )
    (property "License" "Apache-2.0" (at 190.5 44.45 0)
      (effects (font (size 1.27 1.27) (thickness 0.15)) (justify left bottom) hide)
    )
    (pin "1")
    (instances
      (project "kria-k26-devboard"
        (path ""
          (reference "#PWR0192") (unit 1)
        )
      )
    )
  )

  (symbol (lib_id "kria-k26-devboard:GND") (at 247.65 203.2 0) (unit 1)
    (in_bom yes) (on_board yes) (dnp no) (fields_autoplaced)
    (property "Reference" "#PWR0125" (at 247.65 209.55 0)
      (effects (font (size 1.27 1.27)) hide)
    )
    (property "Value" "GND" (at 247.65 207.645 0)
      (effects (font (size 1.27 1.27)))
    )
    (property "Footprint" "" (at 256.54 210.82 0)
      (effects (font (size 1.27 1.27) (thickness 0.15)) (justify left bottom) hide)
    )
    (property "Datasheet" "" (at 256.54 215.9 0)
      (effects (font (size 1.27 1.27) (thickness 0.15)) (justify left bottom) hide)
    )
    (property "Author" "Antmicro" (at 256.54 210.82 0)
      (effects (font (size 1.27 1.27) (thickness 0.15)) (justify left bottom) hide)
    )
    (property "License" "Apache-2.0" (at 256.54 213.36 0)
      (effects (font (size 1.27 1.27) (thickness 0.15)) (justify left bottom) hide)
    )
    (pin "1")
    (instances
      (project "kria-k26-devboard"
        (path ""
          (reference "#PWR0125") (unit 1)
        )
      )
    )
  )

  (symbol (lib_id "kria-k26-devboard:GND") (at 245.11 176.53 0) (unit 1)
    (in_bom yes) (on_board yes) (dnp no)
    (property "Reference" "#PWR0230" (at 245.11 182.88 0)
      (effects (font (size 1.27 1.27)) hide)
    )
    (property "Value" "GND" (at 245.11 180.34 0)
      (effects (font (size 1.27 1.27)))
    )
    (property "Footprint" "" (at 254 184.15 0)
      (effects (font (size 1.27 1.27) (thickness 0.15)) (justify left bottom) hide)
    )
    (property "Datasheet" "" (at 254 189.23 0)
      (effects (font (size 1.27 1.27) (thickness 0.15)) (justify left bottom) hide)
    )
    (property "Author" "Antmicro" (at 254 184.15 0)
      (effects (font (size 1.27 1.27) (thickness 0.15)) (justify left bottom) hide)
    )
    (property "License" "Apache-2.0" (at 254 186.69 0)
      (effects (font (size 1.27 1.27) (thickness 0.15)) (justify left bottom) hide)
    )
    (pin "1")
    (instances
      (project "kria-k26-devboard"
        (path ""
          (reference "#PWR0230") (unit 1)
        )
      )
    )
  )

  (symbol (lib_id "kria-k26-devboard:GND") (at 180.34 38.1 90) (unit 1)
    (in_bom yes) (on_board yes) (dnp no) (fields_autoplaced)
    (property "Reference" "#PWR0190" (at 186.69 38.1 0)
      (effects (font (size 1.27 1.27)) hide)
    )
    (property "Value" "GND" (at 184.15 38.0999 90)
      (effects (font (size 1.27 1.27)) (justify right))
    )
    (property "Footprint" "" (at 187.96 29.21 0)
      (effects (font (size 1.27 1.27) (thickness 0.15)) (justify left bottom) hide)
    )
    (property "Datasheet" "" (at 193.04 29.21 0)
      (effects (font (size 1.27 1.27) (thickness 0.15)) (justify left bottom) hide)
    )
    (property "Author" "Antmicro" (at 187.96 29.21 0)
      (effects (font (size 1.27 1.27) (thickness 0.15)) (justify left bottom) hide)
    )
    (property "License" "Apache-2.0" (at 190.5 29.21 0)
      (effects (font (size 1.27 1.27) (thickness 0.15)) (justify left bottom) hide)
    )
    (pin "1")
    (instances
      (project "kria-k26-devboard"
        (path ""
          (reference "#PWR0190") (unit 1)
        )
      )
    )
  )

  (symbol (lib_id "kria-k26-devboard:GND") (at 278.13 176.53 0) (unit 1)
    (in_bom yes) (on_board yes) (dnp no)
    (property "Reference" "#PWR0251" (at 278.13 182.88 0)
      (effects (font (size 1.27 1.27)) hide)
    )
    (property "Value" "GND" (at 276.225 180.34 0)
      (effects (font (size 1.27 1.27)) (justify left))
    )
    (property "Footprint" "" (at 287.02 184.15 0)
      (effects (font (size 1.27 1.27) (thickness 0.15)) (justify left bottom) hide)
    )
    (property "Datasheet" "" (at 287.02 189.23 0)
      (effects (font (size 1.27 1.27) (thickness 0.15)) (justify left bottom) hide)
    )
    (property "Author" "Antmicro" (at 287.02 184.15 0)
      (effects (font (size 1.27 1.27) (thickness 0.15)) (justify left bottom) hide)
    )
    (property "License" "Apache-2.0" (at 287.02 186.69 0)
      (effects (font (size 1.27 1.27) (thickness 0.15)) (justify left bottom) hide)
    )
    (pin "1")
    (instances
      (project "kria-k26-devboard"
        (path ""
          (reference "#PWR0251") (unit 1)
        )
      )
    )
  )

  (symbol (lib_id "kria-k26-devboard:GND") (at 375.92 176.53 0) (unit 1)
    (in_bom yes) (on_board yes) (dnp no)
    (property "Reference" "#PWR0292" (at 375.92 182.88 0)
      (effects (font (size 1.27 1.27)) hide)
    )
    (property "Value" "GND" (at 375.92 180.34 0)
      (effects (font (size 1.27 1.27)))
    )
    (property "Footprint" "" (at 384.81 184.15 0)
      (effects (font (size 1.27 1.27) (thickness 0.15)) (justify left bottom) hide)
    )
    (property "Datasheet" "" (at 384.81 189.23 0)
      (effects (font (size 1.27 1.27) (thickness 0.15)) (justify left bottom) hide)
    )
    (property "Author" "Antmicro" (at 384.81 184.15 0)
      (effects (font (size 1.27 1.27) (thickness 0.15)) (justify left bottom) hide)
    )
    (property "License" "Apache-2.0" (at 384.81 186.69 0)
      (effects (font (size 1.27 1.27) (thickness 0.15)) (justify left bottom) hide)
    )
    (pin "1")
    (instances
      (project "kria-k26-devboard"
        (path ""
          (reference "#PWR0292") (unit 1)
        )
      )
    )
  )

  (symbol (lib_id "kria-k26-devboard:GND") (at 180.34 45.72 90) (unit 1)
    (in_bom yes) (on_board yes) (dnp no) (fields_autoplaced)
    (property "Reference" "#PWR0191" (at 186.69 45.72 0)
      (effects (font (size 1.27 1.27)) hide)
    )
    (property "Value" "GND" (at 184.15 45.7199 90)
      (effects (font (size 1.27 1.27)) (justify right))
    )
    (property "Footprint" "" (at 187.96 36.83 0)
      (effects (font (size 1.27 1.27) (thickness 0.15)) (justify left bottom) hide)
    )
    (property "Datasheet" "" (at 193.04 36.83 0)
      (effects (font (size 1.27 1.27) (thickness 0.15)) (justify left bottom) hide)
    )
    (property "Author" "Antmicro" (at 187.96 36.83 0)
      (effects (font (size 1.27 1.27) (thickness 0.15)) (justify left bottom) hide)
    )
    (property "License" "Apache-2.0" (at 190.5 36.83 0)
      (effects (font (size 1.27 1.27) (thickness 0.15)) (justify left bottom) hide)
    )
    (pin "1")
    (instances
      (project "kria-k26-devboard"
        (path ""
          (reference "#PWR0191") (unit 1)
        )
      )
    )
  )

  (symbol (lib_id "kria-k26-devboard:GND") (at 340.36 176.53 0) (unit 1)
    (in_bom yes) (on_board yes) (dnp no)
    (property "Reference" "#PWR0273" (at 340.36 182.88 0)
      (effects (font (size 1.27 1.27)) hide)
    )
    (property "Value" "GND" (at 340.36 180.34 0)
      (effects (font (size 1.27 1.27)))
    )
    (property "Footprint" "" (at 349.25 184.15 0)
      (effects (font (size 1.27 1.27) (thickness 0.15)) (justify left bottom) hide)
    )
    (property "Datasheet" "" (at 349.25 189.23 0)
      (effects (font (size 1.27 1.27) (thickness 0.15)) (justify left bottom) hide)
    )
    (property "Author" "Antmicro" (at 349.25 184.15 0)
      (effects (font (size 1.27 1.27) (thickness 0.15)) (justify left bottom) hide)
    )
    (property "License" "Apache-2.0" (at 349.25 186.69 0)
      (effects (font (size 1.27 1.27) (thickness 0.15)) (justify left bottom) hide)
    )
    (pin "1")
    (instances
      (project "kria-k26-devboard"
        (path ""
          (reference "#PWR0273") (unit 1)
        )
      )
    )
  )

  (symbol (lib_id "kria-k26-devboard:GND") (at 180.34 30.48 90) (unit 1)
    (in_bom yes) (on_board yes) (dnp no) (fields_autoplaced)
    (property "Reference" "#PWR0189" (at 186.69 30.48 0)
      (effects (font (size 1.27 1.27)) hide)
    )
    (property "Value" "GND" (at 184.15 30.4799 90)
      (effects (font (size 1.27 1.27)) (justify right))
    )
    (property "Footprint" "" (at 187.96 21.59 0)
      (effects (font (size 1.27 1.27) (thickness 0.15)) (justify left bottom) hide)
    )
    (property "Datasheet" "" (at 193.04 21.59 0)
      (effects (font (size 1.27 1.27) (thickness 0.15)) (justify left bottom) hide)
    )
    (property "Author" "Antmicro" (at 187.96 21.59 0)
      (effects (font (size 1.27 1.27) (thickness 0.15)) (justify left bottom) hide)
    )
    (property "License" "Apache-2.0" (at 190.5 21.59 0)
      (effects (font (size 1.27 1.27) (thickness 0.15)) (justify left bottom) hide)
    )
    (pin "1")
    (instances
      (project "kria-k26-devboard"
        (path ""
          (reference "#PWR0189") (unit 1)
        )
      )
    )
  )

  (symbol (lib_id "kria-k26-devboard:R_10k_0402") (at 213.995 212.09 270) (unit 1)
    (in_bom yes) (on_board yes) (dnp no) (fields_autoplaced)
    (property "Reference" "R155" (at 216.027 213.36 90)
      (effects (font (size 1.524 1.524)) (justify left))
    )
    (property "Value" "R_10k_0402" (at 210.185 212.09 0)
      (effects (font (size 1.27 1.27) (thickness 0.15)) (justify left bottom) hide)
    )
    (property "Footprint" "kria-k26-devboard-footprints:R_0402_1005Metric" (at 219.075 217.17 0)
      (effects (font (size 1.27 1.27) (thickness 0.15)) (justify left bottom) hide)
    )
    (property "Datasheet" "https://www.bourns.com/docs/product-datasheets/cr.pdf" (at 213.995 212.09 0)
      (effects (font (size 1.27 1.27) (thickness 0.15)) (justify left bottom) hide)
    )
    (property "Manufacturer" "Bourns" (at 224.155 217.17 0)
      (effects (font (size 1.27 1.27) (thickness 0.15)) (justify left bottom) hide)
    )
    (property "MPN" "CR0402-FX-1002GLF" (at 221.615 217.17 0)
      (effects (font (size 1.27 1.27) (thickness 0.15)) (justify left bottom) hide)
    )
    (property "Val" "10k" (at 216.027 216.5349 90)
      (effects (font (size 1.27 1.27) (thickness 0.15)) (justify left))
    )
    (property "License" "Apache-2.0" (at 188.595 232.41 0)
      (effects (font (size 1.27 1.27) (thickness 0.15)) (justify left bottom) hide)
    )
    (property "Author" "Antmicro" (at 186.055 232.41 0)
      (effects (font (size 1.27 1.27) (thickness 0.15)) (justify left bottom) hide)
    )
    (property "Tolerance" "1%" (at 203.835 232.41 0)
      (effects (font (size 1.27 1.27)) (justify left bottom) hide)
    )
    (pin "1")
    (pin "2")
    (instances
      (project "kria-k26-devboard"
        (path ""
          (reference "R155") (unit 1)
        )
      )
    )
  )

  (symbol (lib_id "kria-k26-devboard:GND") (at 213.995 217.17 0) (unit 1)
    (in_bom yes) (on_board yes) (dnp no) (fields_autoplaced)
    (property "Reference" "#PWR0404" (at 213.995 223.52 0)
      (effects (font (size 1.27 1.27)) hide)
    )
    (property "Value" "GND" (at 213.995 222.504 0)
      (effects (font (size 1.27 1.27)))
    )
    (property "Footprint" "" (at 222.885 224.79 0)
      (effects (font (size 1.27 1.27) (thickness 0.15)) (justify left bottom) hide)
    )
    (property "Datasheet" "" (at 222.885 229.87 0)
      (effects (font (size 1.27 1.27) (thickness 0.15)) (justify left bottom) hide)
    )
    (property "Author" "Antmicro" (at 222.885 224.79 0)
      (effects (font (size 1.27 1.27) (thickness 0.15)) (justify left bottom) hide)
    )
    (property "License" "Apache-2.0" (at 222.885 227.33 0)
      (effects (font (size 1.27 1.27) (thickness 0.15)) (justify left bottom) hide)
    )
    (pin "1")
    (instances
      (project "kria-k26-devboard"
        (path ""
          (reference "#PWR0404") (unit 1)
        )
      )
    )
  )

  (symbol (lib_id "kria-k26-devboard:GND") (at 180.34 71.12 90) (unit 1)
    (in_bom yes) (on_board yes) (dnp no) (fields_autoplaced)
    (property "Reference" "#PWR0194" (at 186.69 71.12 0)
      (effects (font (size 1.27 1.27)) hide)
    )
    (property "Value" "GND" (at 184.15 71.1199 90)
      (effects (font (size 1.27 1.27)) (justify right))
    )
    (property "Footprint" "" (at 187.96 62.23 0)
      (effects (font (size 1.27 1.27) (thickness 0.15)) (justify left bottom) hide)
    )
    (property "Datasheet" "" (at 193.04 62.23 0)
      (effects (font (size 1.27 1.27) (thickness 0.15)) (justify left bottom) hide)
    )
    (property "Author" "Antmicro" (at 187.96 62.23 0)
      (effects (font (size 1.27 1.27) (thickness 0.15)) (justify left bottom) hide)
    )
    (property "License" "Apache-2.0" (at 190.5 62.23 0)
      (effects (font (size 1.27 1.27) (thickness 0.15)) (justify left bottom) hide)
    )
    (pin "1")
    (instances
      (project "kria-k26-devboard"
        (path ""
          (reference "#PWR0194") (unit 1)
        )
      )
    )
  )

  (symbol (lib_id "kria-k26-devboard:GND") (at 180.34 81.28 90) (unit 1)
    (in_bom yes) (on_board yes) (dnp no) (fields_autoplaced)
    (property "Reference" "#PWR0195" (at 186.69 81.28 0)
      (effects (font (size 1.27 1.27)) hide)
    )
    (property "Value" "GND" (at 184.15 81.2799 90)
      (effects (font (size 1.27 1.27)) (justify right))
    )
    (property "Footprint" "" (at 187.96 72.39 0)
      (effects (font (size 1.27 1.27) (thickness 0.15)) (justify left bottom) hide)
    )
    (property "Datasheet" "" (at 193.04 72.39 0)
      (effects (font (size 1.27 1.27) (thickness 0.15)) (justify left bottom) hide)
    )
    (property "Author" "Antmicro" (at 187.96 72.39 0)
      (effects (font (size 1.27 1.27) (thickness 0.15)) (justify left bottom) hide)
    )
    (property "License" "Apache-2.0" (at 190.5 72.39 0)
      (effects (font (size 1.27 1.27) (thickness 0.15)) (justify left bottom) hide)
    )
    (pin "1")
    (instances
      (project "kria-k26-devboard"
        (path ""
          (reference "#PWR0195") (unit 1)
        )
      )
    )
  )

  (symbol (lib_id "kria-k26-devboard:GND") (at 180.34 91.44 90) (unit 1)
    (in_bom yes) (on_board yes) (dnp no) (fields_autoplaced)
    (property "Reference" "#PWR0196" (at 186.69 91.44 0)
      (effects (font (size 1.27 1.27)) hide)
    )
    (property "Value" "GND" (at 184.15 91.4399 90)
      (effects (font (size 1.27 1.27)) (justify right))
    )
    (property "Footprint" "" (at 187.96 82.55 0)
      (effects (font (size 1.27 1.27) (thickness 0.15)) (justify left bottom) hide)
    )
    (property "Datasheet" "" (at 193.04 82.55 0)
      (effects (font (size 1.27 1.27) (thickness 0.15)) (justify left bottom) hide)
    )
    (property "Author" "Antmicro" (at 187.96 82.55 0)
      (effects (font (size 1.27 1.27) (thickness 0.15)) (justify left bottom) hide)
    )
    (property "License" "Apache-2.0" (at 190.5 82.55 0)
      (effects (font (size 1.27 1.27) (thickness 0.15)) (justify left bottom) hide)
    )
    (pin "1")
    (instances
      (project "kria-k26-devboard"
        (path ""
          (reference "#PWR0196") (unit 1)
        )
      )
    )
  )

  (symbol (lib_id "kria-k26-devboard:GND") (at 180.34 101.6 90) (unit 1)
    (in_bom yes) (on_board yes) (dnp no) (fields_autoplaced)
    (property "Reference" "#PWR0197" (at 186.69 101.6 0)
      (effects (font (size 1.27 1.27)) hide)
    )
    (property "Value" "GND" (at 184.15 101.5999 90)
      (effects (font (size 1.27 1.27)) (justify right))
    )
    (property "Footprint" "" (at 187.96 92.71 0)
      (effects (font (size 1.27 1.27) (thickness 0.15)) (justify left bottom) hide)
    )
    (property "Datasheet" "" (at 193.04 92.71 0)
      (effects (font (size 1.27 1.27) (thickness 0.15)) (justify left bottom) hide)
    )
    (property "Author" "Antmicro" (at 187.96 92.71 0)
      (effects (font (size 1.27 1.27) (thickness 0.15)) (justify left bottom) hide)
    )
    (property "License" "Apache-2.0" (at 190.5 92.71 0)
      (effects (font (size 1.27 1.27) (thickness 0.15)) (justify left bottom) hide)
    )
    (pin "1")
    (instances
      (project "kria-k26-devboard"
        (path ""
          (reference "#PWR0197") (unit 1)
        )
      )
    )
  )

  (symbol (lib_id "kria-k26-devboard:GND") (at 180.34 111.76 90) (unit 1)
    (in_bom yes) (on_board yes) (dnp no) (fields_autoplaced)
    (property "Reference" "#PWR0198" (at 186.69 111.76 0)
      (effects (font (size 1.27 1.27)) hide)
    )
    (property "Value" "GND" (at 184.15 111.7599 90)
      (effects (font (size 1.27 1.27)) (justify right))
    )
    (property "Footprint" "" (at 187.96 102.87 0)
      (effects (font (size 1.27 1.27) (thickness 0.15)) (justify left bottom) hide)
    )
    (property "Datasheet" "" (at 193.04 102.87 0)
      (effects (font (size 1.27 1.27) (thickness 0.15)) (justify left bottom) hide)
    )
    (property "Author" "Antmicro" (at 187.96 102.87 0)
      (effects (font (size 1.27 1.27) (thickness 0.15)) (justify left bottom) hide)
    )
    (property "License" "Apache-2.0" (at 190.5 102.87 0)
      (effects (font (size 1.27 1.27) (thickness 0.15)) (justify left bottom) hide)
    )
    (pin "1")
    (instances
      (project "kria-k26-devboard"
        (path ""
          (reference "#PWR0198") (unit 1)
        )
      )
    )
  )

  (symbol (lib_id "kria-k26-devboard:GND") (at 180.34 152.4 90) (unit 1)
    (in_bom yes) (on_board yes) (dnp no) (fields_autoplaced)
    (property "Reference" "#PWR0203" (at 186.69 152.4 0)
      (effects (font (size 1.27 1.27)) hide)
    )
    (property "Value" "GND" (at 184.15 152.3999 90)
      (effects (font (size 1.27 1.27)) (justify right))
    )
    (property "Footprint" "" (at 187.96 143.51 0)
      (effects (font (size 1.27 1.27) (thickness 0.15)) (justify left bottom) hide)
    )
    (property "Datasheet" "" (at 193.04 143.51 0)
      (effects (font (size 1.27 1.27) (thickness 0.15)) (justify left bottom) hide)
    )
    (property "Author" "Antmicro" (at 187.96 143.51 0)
      (effects (font (size 1.27 1.27) (thickness 0.15)) (justify left bottom) hide)
    )
    (property "License" "Apache-2.0" (at 190.5 143.51 0)
      (effects (font (size 1.27 1.27) (thickness 0.15)) (justify left bottom) hide)
    )
    (pin "1")
    (instances
      (project "kria-k26-devboard"
        (path ""
          (reference "#PWR0203") (unit 1)
        )
      )
    )
  )

  (symbol (lib_id "kria-k26-devboard:GND") (at 180.34 142.24 90) (unit 1)
    (in_bom yes) (on_board yes) (dnp no) (fields_autoplaced)
    (property "Reference" "#PWR0201" (at 186.69 142.24 0)
      (effects (font (size 1.27 1.27)) hide)
    )
    (property "Value" "GND" (at 184.15 142.2399 90)
      (effects (font (size 1.27 1.27)) (justify right))
    )
    (property "Footprint" "" (at 187.96 133.35 0)
      (effects (font (size 1.27 1.27) (thickness 0.15)) (justify left bottom) hide)
    )
    (property "Datasheet" "" (at 193.04 133.35 0)
      (effects (font (size 1.27 1.27) (thickness 0.15)) (justify left bottom) hide)
    )
    (property "Author" "Antmicro" (at 187.96 133.35 0)
      (effects (font (size 1.27 1.27) (thickness 0.15)) (justify left bottom) hide)
    )
    (property "License" "Apache-2.0" (at 190.5 133.35 0)
      (effects (font (size 1.27 1.27) (thickness 0.15)) (justify left bottom) hide)
    )
    (pin "1")
    (instances
      (project "kria-k26-devboard"
        (path ""
          (reference "#PWR0201") (unit 1)
        )
      )
    )
  )

  (symbol (lib_id "kria-k26-devboard:GND") (at 180.34 144.78 90) (unit 1)
    (in_bom yes) (on_board yes) (dnp no) (fields_autoplaced)
    (property "Reference" "#PWR0202" (at 186.69 144.78 0)
      (effects (font (size 1.27 1.27)) hide)
    )
    (property "Value" "GND" (at 184.15 144.7799 90)
      (effects (font (size 1.27 1.27)) (justify right))
    )
    (property "Footprint" "" (at 187.96 135.89 0)
      (effects (font (size 1.27 1.27) (thickness 0.15)) (justify left bottom) hide)
    )
    (property "Datasheet" "" (at 193.04 135.89 0)
      (effects (font (size 1.27 1.27) (thickness 0.15)) (justify left bottom) hide)
    )
    (property "Author" "Antmicro" (at 187.96 135.89 0)
      (effects (font (size 1.27 1.27) (thickness 0.15)) (justify left bottom) hide)
    )
    (property "License" "Apache-2.0" (at 190.5 135.89 0)
      (effects (font (size 1.27 1.27) (thickness 0.15)) (justify left bottom) hide)
    )
    (pin "1")
    (instances
      (project "kria-k26-devboard"
        (path ""
          (reference "#PWR0202") (unit 1)
        )
      )
    )
  )

  (symbol (lib_id "kria-k26-devboard:GND") (at 180.34 162.56 90) (unit 1)
    (in_bom yes) (on_board yes) (dnp no) (fields_autoplaced)
    (property "Reference" "#PWR0205" (at 186.69 162.56 0)
      (effects (font (size 1.27 1.27)) hide)
    )
    (property "Value" "GND" (at 184.15 162.5599 90)
      (effects (font (size 1.27 1.27)) (justify right))
    )
    (property "Footprint" "" (at 187.96 153.67 0)
      (effects (font (size 1.27 1.27) (thickness 0.15)) (justify left bottom) hide)
    )
    (property "Datasheet" "" (at 193.04 153.67 0)
      (effects (font (size 1.27 1.27) (thickness 0.15)) (justify left bottom) hide)
    )
    (property "Author" "Antmicro" (at 187.96 153.67 0)
      (effects (font (size 1.27 1.27) (thickness 0.15)) (justify left bottom) hide)
    )
    (property "License" "Apache-2.0" (at 190.5 153.67 0)
      (effects (font (size 1.27 1.27) (thickness 0.15)) (justify left bottom) hide)
    )
    (pin "1")
    (instances
      (project "kria-k26-devboard"
        (path ""
          (reference "#PWR0205") (unit 1)
        )
      )
    )
  )

  (symbol (lib_id "kria-k26-devboard:GND") (at 180.34 154.94 90) (unit 1)
    (in_bom yes) (on_board yes) (dnp no) (fields_autoplaced)
    (property "Reference" "#PWR0204" (at 186.69 154.94 0)
      (effects (font (size 1.27 1.27)) hide)
    )
    (property "Value" "GND" (at 184.15 154.9399 90)
      (effects (font (size 1.27 1.27)) (justify right))
    )
    (property "Footprint" "" (at 187.96 146.05 0)
      (effects (font (size 1.27 1.27) (thickness 0.15)) (justify left bottom) hide)
    )
    (property "Datasheet" "" (at 193.04 146.05 0)
      (effects (font (size 1.27 1.27) (thickness 0.15)) (justify left bottom) hide)
    )
    (property "Author" "Antmicro" (at 187.96 146.05 0)
      (effects (font (size 1.27 1.27) (thickness 0.15)) (justify left bottom) hide)
    )
    (property "License" "Apache-2.0" (at 190.5 146.05 0)
      (effects (font (size 1.27 1.27) (thickness 0.15)) (justify left bottom) hide)
    )
    (pin "1")
    (instances
      (project "kria-k26-devboard"
        (path ""
          (reference "#PWR0204") (unit 1)
        )
      )
    )
  )

  (symbol (lib_id "kria-k26-devboard:GND") (at 180.34 172.72 90) (unit 1)
    (in_bom yes) (on_board yes) (dnp no) (fields_autoplaced)
    (property "Reference" "#PWR0207" (at 186.69 172.72 0)
      (effects (font (size 1.27 1.27)) hide)
    )
    (property "Value" "GND" (at 184.15 172.7199 90)
      (effects (font (size 1.27 1.27)) (justify right))
    )
    (property "Footprint" "" (at 187.96 163.83 0)
      (effects (font (size 1.27 1.27) (thickness 0.15)) (justify left bottom) hide)
    )
    (property "Datasheet" "" (at 193.04 163.83 0)
      (effects (font (size 1.27 1.27) (thickness 0.15)) (justify left bottom) hide)
    )
    (property "Author" "Antmicro" (at 187.96 163.83 0)
      (effects (font (size 1.27 1.27) (thickness 0.15)) (justify left bottom) hide)
    )
    (property "License" "Apache-2.0" (at 190.5 163.83 0)
      (effects (font (size 1.27 1.27) (thickness 0.15)) (justify left bottom) hide)
    )
    (pin "1")
    (instances
      (project "kria-k26-devboard"
        (path ""
          (reference "#PWR0207") (unit 1)
        )
      )
    )
  )

  (symbol (lib_id "kria-k26-devboard:GND") (at 180.34 165.1 90) (unit 1)
    (in_bom yes) (on_board yes) (dnp no) (fields_autoplaced)
    (property "Reference" "#PWR0206" (at 186.69 165.1 0)
      (effects (font (size 1.27 1.27)) hide)
    )
    (property "Value" "GND" (at 184.15 165.0999 90)
      (effects (font (size 1.27 1.27)) (justify right))
    )
    (property "Footprint" "" (at 187.96 156.21 0)
      (effects (font (size 1.27 1.27) (thickness 0.15)) (justify left bottom) hide)
    )
    (property "Datasheet" "" (at 193.04 156.21 0)
      (effects (font (size 1.27 1.27) (thickness 0.15)) (justify left bottom) hide)
    )
    (property "Author" "Antmicro" (at 187.96 156.21 0)
      (effects (font (size 1.27 1.27) (thickness 0.15)) (justify left bottom) hide)
    )
    (property "License" "Apache-2.0" (at 190.5 156.21 0)
      (effects (font (size 1.27 1.27) (thickness 0.15)) (justify left bottom) hide)
    )
    (pin "1")
    (instances
      (project "kria-k26-devboard"
        (path ""
          (reference "#PWR0206") (unit 1)
        )
      )
    )
  )

  (symbol (lib_id "kria-k26-devboard:GND") (at 180.34 121.92 90) (unit 1)
    (in_bom yes) (on_board yes) (dnp no) (fields_autoplaced)
    (property "Reference" "#PWR0199" (at 186.69 121.92 0)
      (effects (font (size 1.27 1.27)) hide)
    )
    (property "Value" "GND" (at 184.15 121.9199 90)
      (effects (font (size 1.27 1.27)) (justify right))
    )
    (property "Footprint" "" (at 187.96 113.03 0)
      (effects (font (size 1.27 1.27) (thickness 0.15)) (justify left bottom) hide)
    )
    (property "Datasheet" "" (at 193.04 113.03 0)
      (effects (font (size 1.27 1.27) (thickness 0.15)) (justify left bottom) hide)
    )
    (property "Author" "Antmicro" (at 187.96 113.03 0)
      (effects (font (size 1.27 1.27) (thickness 0.15)) (justify left bottom) hide)
    )
    (property "License" "Apache-2.0" (at 190.5 113.03 0)
      (effects (font (size 1.27 1.27) (thickness 0.15)) (justify left bottom) hide)
    )
    (pin "1")
    (instances
      (project "kria-k26-devboard"
        (path ""
          (reference "#PWR0199") (unit 1)
        )
      )
    )
  )

  (symbol (lib_id "kria-k26-devboard:GND") (at 180.34 132.08 90) (unit 1)
    (in_bom yes) (on_board yes) (dnp no) (fields_autoplaced)
    (property "Reference" "#PWR0200" (at 186.69 132.08 0)
      (effects (font (size 1.27 1.27)) hide)
    )
    (property "Value" "GND" (at 184.15 132.0799 90)
      (effects (font (size 1.27 1.27)) (justify right))
    )
    (property "Footprint" "" (at 187.96 123.19 0)
      (effects (font (size 1.27 1.27) (thickness 0.15)) (justify left bottom) hide)
    )
    (property "Datasheet" "" (at 193.04 123.19 0)
      (effects (font (size 1.27 1.27) (thickness 0.15)) (justify left bottom) hide)
    )
    (property "Author" "Antmicro" (at 187.96 123.19 0)
      (effects (font (size 1.27 1.27) (thickness 0.15)) (justify left bottom) hide)
    )
    (property "License" "Apache-2.0" (at 190.5 123.19 0)
      (effects (font (size 1.27 1.27) (thickness 0.15)) (justify left bottom) hide)
    )
    (pin "1")
    (instances
      (project "kria-k26-devboard"
        (path ""
          (reference "#PWR0200") (unit 1)
        )
      )
    )
  )

  (symbol (lib_id "kria-k26-devboard:DTC014T_SOT-416") (at 97.155 215.9 0) (unit 1)
    (in_bom yes) (on_board yes) (dnp no) (fields_autoplaced)
    (property "Reference" "Q7" (at 107.315 214.6299 0)
      (effects (font (size 1.27 1.27)) (justify left))
    )
    (property "Value" "DTC014T_SOT-416" (at 107.315 217.1699 0)
      (effects (font (size 1.27 1.27) (thickness 0.15)) (justify left) hide)
    )
    (property "Footprint" "kria-k26-devboard-footprints:SOT-416" (at 102.235 223.52 0)
      (effects (font (size 1.27 1.27) (thickness 0.15)) (justify left bottom) hide)
    )
    (property "Datasheet" "https://www.rohm.com/datasheet?p=DTC014TEB&dist=Mouser&media=referral&source=mouser.com&campaign=Mouser" (at 97.155 215.9 0)
      (effects (font (size 1.27 1.27) (thickness 0.15)) (justify left bottom) hide)
    )
    (property "Manufacturer" "ROHM Semiconductor" (at 112.395 218.44 0)
      (effects (font (size 1.27 1.27) (thickness 0.15)) (justify left bottom) hide)
    )
    (property "MPN" "DTC014TEBTL" (at 107.315 217.1699 0)
      (effects (font (size 1.27 1.27) (thickness 0.15)) (justify left))
    )
    (property "Author" "Antmicro" (at 122.555 236.22 0)
      (effects (font (size 1.27 1.27) (thickness 0.15)) (justify left bottom) hide)
    )
    (property "License" "Apache-2.0" (at 122.555 238.76 0)
      (effects (font (size 1.27 1.27) (thickness 0.15)) (justify left bottom) hide)
    )
    (pin "1")
    (pin "2")
    (pin "3")
    (instances
      (project "kria-k26-devboard"
        (path ""
          (reference "Q7") (unit 1)
        )
      )
    )
  )

  (symbol (lib_id "kria-k26-devboard:PJA3441") (at 104.775 204.47 270) (mirror x) (unit 1)
    (in_bom yes) (on_board yes) (dnp no) (fields_autoplaced)
    (property "Reference" "Q6" (at 107.315 189.23 90)
      (effects (font (size 1.27 1.27)))
    )
    (property "Value" "PJA3441" (at 107.315 191.77 90)
      (effects (font (size 1.27 1.27) (thickness 0.15)))
    )
    (property "Footprint" "kria-k26-devboard-footprints:SOT-23-3" (at 104.775 204.47 0)
      (effects (font (size 1.27 1.27) (thickness 0.15)) (justify left bottom) hide)
    )
    (property "Datasheet" "https://www.mouser.pl/datasheet/2/1057/PJA3441-1867252.pdf" (at 104.775 204.47 0)
      (effects (font (size 1.27 1.27) (thickness 0.15)) (justify left bottom) hide)
    )
    (property "Manufacturer" "Panjit" (at 108.585 196.85 0)
      (effects (font (size 1.27 1.27) (thickness 0.15)) (justify left bottom) hide)
    )
    (property "MPN" "PJA3441_R1_00001" (at 111.125 190.5 0)
      (effects (font (size 1.27 1.27) (thickness 0.15)) (justify left bottom) hide)
    )
    (property "Author" "Antmicro" (at 95.885 184.15 0)
      (effects (font (size 1.27 1.27) (thickness 0.15)) (justify left bottom) hide)
    )
    (property "License" "Apache-2.0" (at 93.345 184.15 0)
      (effects (font (size 1.27 1.27) (thickness 0.15)) (justify left bottom) hide)
    )
    (pin "1")
    (pin "2")
    (pin "3")
    (instances
      (project "kria-k26-devboard"
        (path ""
          (reference "Q6") (unit 1)
        )
      )
    )
  )

  (symbol (lib_id "kria-k26-devboard:R_100k_0402") (at 99.695 199.39 270) (unit 1)
    (in_bom yes) (on_board yes) (dnp no)
    (property "Reference" "R83" (at 97.79 200.66 90)
      (effects (font (size 1.524 1.524)) (justify right))
    )
    (property "Value" "R_100k_0402" (at 95.885 199.39 0)
      (effects (font (size 1.27 1.27) (thickness 0.15)) (justify left bottom) hide)
    )
    (property "Footprint" "kria-k26-devboard-footprints:R_0402_1005Metric" (at 104.775 204.47 0)
      (effects (font (size 1.27 1.27) (thickness 0.15)) (justify left bottom) hide)
    )
    (property "Datasheet" "https://www.bourns.com/docs/product-datasheets/cr.pdf" (at 99.695 199.39 0)
      (effects (font (size 1.27 1.27) (thickness 0.15)) (justify left bottom) hide)
    )
    (property "Manufacturer" "Bourns" (at 109.855 204.47 0)
      (effects (font (size 1.27 1.27) (thickness 0.15)) (justify left bottom) hide)
    )
    (property "MPN" "CR0402-FX-1003GLF" (at 107.315 204.47 0)
      (effects (font (size 1.27 1.27) (thickness 0.15)) (justify left bottom) hide)
    )
    (property "Val" "100k" (at 97.79 203.835 90)
      (effects (font (size 1.27 1.27) (thickness 0.15)) (justify right))
    )
    (property "License" "Apache-2.0" (at 74.295 219.71 0)
      (effects (font (size 1.27 1.27) (thickness 0.15)) (justify left bottom) hide)
    )
    (property "Author" "Antmicro" (at 71.755 219.71 0)
      (effects (font (size 1.27 1.27) (thickness 0.15)) (justify left bottom) hide)
    )
    (property "Tolerance" "1%" (at 89.535 219.71 0)
      (effects (font (size 1.27 1.27)) (justify left bottom) hide)
    )
    (pin "1")
    (pin "2")
    (instances
      (project "kria-k26-devboard"
        (path ""
          (reference "R83") (unit 1)
        )
      )
    )
  )

  (symbol (lib_id "kria-k26-devboard:C_4u7_0402") (at 304.8 198.12 270) (unit 1)
    (in_bom yes) (on_board yes) (dnp no)
    (property "Reference" "C123" (at 305.435 198.755 90)
      (effects (font (size 1.524 1.524)) (justify left))
    )
    (property "Value" "C_4u7_0402" (at 300.99 198.12 0)
      (effects (font (size 1.27 1.27) (thickness 0.15)) (justify left bottom) hide)
    )
    (property "Footprint" "kria-k26-devboard-footprints:C_0402_1005Metric" (at 309.88 203.2 0)
      (effects (font (size 1.27 1.27) (thickness 0.15)) (justify left bottom) hide)
    )
    (property "Datasheet" " " (at 304.8 198.12 0)
      (effects (font (size 1.27 1.27) (thickness 0.15)) (justify left bottom) hide)
    )
    (property "Manufacturer" "Murata" (at 314.96 203.2 0)
      (effects (font (size 1.27 1.27) (thickness 0.15)) (justify left bottom) hide)
    )
    (property "MPN" "GRM155R61A475MEAAD" (at 312.42 203.2 0)
      (effects (font (size 1.27 1.27) (thickness 0.15)) (justify left bottom) hide)
    )
    (property "Val" "4u7" (at 305.435 202.565 90)
      (effects (font (size 1.27 1.27) (thickness 0.15)) (justify left))
    )
    (property "License" "Apache-2.0" (at 281.94 218.44 0)
      (effects (font (size 1.27 1.27) (thickness 0.15)) (justify left bottom) hide)
    )
    (property "Author" "Antmicro" (at 279.4 218.44 0)
      (effects (font (size 1.27 1.27) (thickness 0.15)) (justify left bottom) hide)
    )
    (property "Voltage" "" (at 276.86 218.44 0)
      (effects (font (size 1.27 1.27)) (justify left bottom) hide)
    )
    (property "Dielectric" "" (at 274.32 218.44 0)
      (effects (font (size 1.27 1.27)) (justify left bottom) hide)
    )
    (pin "1")
    (pin "2")
    (instances
      (project "kria-k26-devboard"
        (path ""
          (reference "C123") (unit 1)
        )
      )
    )
  )

  (symbol (lib_id "kria-k26-devboard:C_100n_0402") (at 314.96 198.12 270) (unit 1)
    (in_bom yes) (on_board yes) (dnp no)
    (property "Reference" "C124" (at 315.595 198.755 90)
      (effects (font (size 1.524 1.524)) (justify left))
    )
    (property "Value" "C_100n_0402" (at 311.15 198.12 0)
      (effects (font (size 1.27 1.27) (thickness 0.15)) (justify left bottom) hide)
    )
    (property "Footprint" "kria-k26-devboard-footprints:C_0402_1005Metric" (at 320.04 203.2 0)
      (effects (font (size 1.27 1.27) (thickness 0.15)) (justify left bottom) hide)
    )
    (property "Datasheet" "https://search.murata.co.jp/Ceramy/image/img/A01X/G101/ENG/GRM155R61H104KE14-01.pdf" (at 314.96 198.12 0)
      (effects (font (size 1.27 1.27) (thickness 0.15)) (justify left bottom) hide)
    )
    (property "Manufacturer" "Murata" (at 325.12 203.2 0)
      (effects (font (size 1.27 1.27) (thickness 0.15)) (justify left bottom) hide)
    )
    (property "MPN" "GRM155R61H104KE14D" (at 322.58 203.2 0)
      (effects (font (size 1.27 1.27) (thickness 0.15)) (justify left bottom) hide)
    )
    (property "Val" "100n" (at 315.595 202.565 90)
      (effects (font (size 1.27 1.27) (thickness 0.15)) (justify left))
    )
    (property "License" "Apache-2.0" (at 292.1 218.44 0)
      (effects (font (size 1.27 1.27) (thickness 0.15)) (justify left bottom) hide)
    )
    (property "Author" "Antmicro" (at 289.56 218.44 0)
      (effects (font (size 1.27 1.27) (thickness 0.15)) (justify left bottom) hide)
    )
    (property "Voltage" "50V" (at 287.02 218.44 0)
      (effects (font (size 1.27 1.27)) (justify left bottom) hide)
    )
    (property "Dielectric" "X5R" (at 284.48 218.44 0)
      (effects (font (size 1.27 1.27)) (justify left bottom) hide)
    )
    (pin "1")
    (pin "2")
    (instances
      (project "kria-k26-devboard"
        (path ""
          (reference "C124") (unit 1)
        )
      )
    )
  )

  (symbol (lib_id "kria-k26-devboard:GND") (at 104.775 220.98 0) (unit 1)
    (in_bom yes) (on_board yes) (dnp no) (fields_autoplaced)
    (property "Reference" "#PWR0166" (at 104.775 227.33 0)
      (effects (font (size 1.27 1.27)) hide)
    )
    (property "Value" "GND" (at 104.775 226.06 0)
      (effects (font (size 1.27 1.27)))
    )
    (property "Footprint" "" (at 113.665 228.6 0)
      (effects (font (size 1.27 1.27) (thickness 0.15)) (justify left bottom) hide)
    )
    (property "Datasheet" "" (at 113.665 233.68 0)
      (effects (font (size 1.27 1.27) (thickness 0.15)) (justify left bottom) hide)
    )
    (property "Author" "Antmicro" (at 113.665 228.6 0)
      (effects (font (size 1.27 1.27) (thickness 0.15)) (justify left bottom) hide)
    )
    (property "License" "Apache-2.0" (at 113.665 231.14 0)
      (effects (font (size 1.27 1.27) (thickness 0.15)) (justify left bottom) hide)
    )
    (pin "1")
    (instances
      (project "kria-k26-devboard"
        (path ""
          (reference "#PWR0166") (unit 1)
        )
      )
    )
  )

  (symbol (lib_id "kria-k26-devboard:C_100n_0402") (at 326.39 198.12 270) (unit 1)
    (in_bom yes) (on_board yes) (dnp no)
    (property "Reference" "C125" (at 327.025 198.755 90)
      (effects (font (size 1.524 1.524)) (justify left))
    )
    (property "Value" "C_100n_0402" (at 322.58 198.12 0)
      (effects (font (size 1.27 1.27) (thickness 0.15)) (justify left bottom) hide)
    )
    (property "Footprint" "kria-k26-devboard-footprints:C_0402_1005Metric" (at 331.47 203.2 0)
      (effects (font (size 1.27 1.27) (thickness 0.15)) (justify left bottom) hide)
    )
    (property "Datasheet" "https://search.murata.co.jp/Ceramy/image/img/A01X/G101/ENG/GRM155R61H104KE14-01.pdf" (at 326.39 198.12 0)
      (effects (font (size 1.27 1.27) (thickness 0.15)) (justify left bottom) hide)
    )
    (property "Manufacturer" "Murata" (at 336.55 203.2 0)
      (effects (font (size 1.27 1.27) (thickness 0.15)) (justify left bottom) hide)
    )
    (property "MPN" "GRM155R61H104KE14D" (at 334.01 203.2 0)
      (effects (font (size 1.27 1.27) (thickness 0.15)) (justify left bottom) hide)
    )
    (property "Val" "100n" (at 327.025 202.565 90)
      (effects (font (size 1.27 1.27) (thickness 0.15)) (justify left))
    )
    (property "License" "Apache-2.0" (at 303.53 218.44 0)
      (effects (font (size 1.27 1.27) (thickness 0.15)) (justify left bottom) hide)
    )
    (property "Author" "Antmicro" (at 300.99 218.44 0)
      (effects (font (size 1.27 1.27) (thickness 0.15)) (justify left bottom) hide)
    )
    (property "Voltage" "50V" (at 298.45 218.44 0)
      (effects (font (size 1.27 1.27)) (justify left bottom) hide)
    )
    (property "Dielectric" "X5R" (at 295.91 218.44 0)
      (effects (font (size 1.27 1.27)) (justify left bottom) hide)
    )
    (pin "1")
    (pin "2")
    (instances
      (project "kria-k26-devboard"
        (path ""
          (reference "C125") (unit 1)
        )
      )
    )
  )

  (symbol (lib_id "kria-k26-devboard:GND") (at 304.8 203.2 0) (unit 1)
    (in_bom yes) (on_board yes) (dnp no) (fields_autoplaced)
    (property "Reference" "#PWR0167" (at 304.8 209.55 0)
      (effects (font (size 1.27 1.27)) hide)
    )
    (property "Value" "GND" (at 304.8 208.28 0)
      (effects (font (size 1.27 1.27)))
    )
    (property "Footprint" "" (at 313.69 210.82 0)
      (effects (font (size 1.27 1.27) (thickness 0.15)) (justify left bottom) hide)
    )
    (property "Datasheet" "" (at 313.69 215.9 0)
      (effects (font (size 1.27 1.27) (thickness 0.15)) (justify left bottom) hide)
    )
    (property "Author" "Antmicro" (at 313.69 210.82 0)
      (effects (font (size 1.27 1.27) (thickness 0.15)) (justify left bottom) hide)
    )
    (property "License" "Apache-2.0" (at 313.69 213.36 0)
      (effects (font (size 1.27 1.27) (thickness 0.15)) (justify left bottom) hide)
    )
    (pin "1")
    (instances
      (project "kria-k26-devboard"
        (path ""
          (reference "#PWR0167") (unit 1)
        )
      )
    )
  )

  (symbol (lib_id "kria-k26-devboard:1N4148WS") (at 116.205 207.01 90) (unit 1)
    (in_bom yes) (on_board yes) (dnp no)
    (property "Reference" "D3" (at 116.84 200.66 90)
      (effects (font (size 1.524 1.524)) (justify right))
    )
    (property "Value" "1N4148WS" (at 116.84 205.74 90)
      (effects (font (size 1.27 1.27) (thickness 0.15)) (justify right))
    )
    (property "Footprint" "kria-k26-devboard-footprints:D_SOD-323F" (at 111.125 201.93 0)
      (effects (font (size 1.27 1.27) (thickness 0.15)) (justify left bottom) hide)
    )
    (property "Datasheet" "https://www.onsemi.com/pub/Collateral/1N914BWS-D.pdf" (at 108.585 201.93 0)
      (effects (font (size 1.27 1.27) (thickness 0.15)) (justify left bottom) hide)
    )
    (property "MPN" "1N4148WS" (at 103.505 201.93 0)
      (effects (font (size 1.27 1.27) (thickness 0.15)) (justify left bottom) hide)
    )
    (property "Manufacturer" "ON Semiconductor" (at 88.265 201.93 0)
      (effects (font (size 1.27 1.27) (thickness 0.15)) (justify left bottom) hide)
    )
    (property "Author" "Antmicro" (at 136.525 185.42 0)
      (effects (font (size 1.27 1.27) (thickness 0.15)) (justify left bottom) hide)
    )
    (property "License" "Apache-2.0" (at 139.065 185.42 0)
      (effects (font (size 1.27 1.27) (thickness 0.15)) (justify left bottom) hide)
    )
    (pin "A")
    (pin "K")
    (instances
      (project "kria-k26-devboard"
        (path ""
          (reference "D3") (unit 1)
        )
      )
    )
  )

  (symbol (lib_id "kria-k26-devboard:FB_120Z_1.3A_Murata-BLM15PD_0402") (at 160.02 213.36 0) (unit 1)
    (in_bom yes) (on_board yes) (dnp no) (fields_autoplaced)
    (property "Reference" "FB2" (at 162.5219 218.44 0)
      (effects (font (size 1.524 1.524)))
    )
    (property "Value" "FB_120Z_1.3A_0402" (at 162.5219 220.98 0)
      (effects (font (size 1.27 1.27) (thickness 0.15)))
    )
    (property "Footprint" "kria-k26-devboard-footprints:FB_0402_1005Metric" (at 165.1 208.28 0)
      (effects (font (size 1.27 1.27) (thickness 0.15)) (justify left bottom) hide)
    )
    (property "Datasheet" "https://www.murata.com/en-us/products/productdata/8796740059166/ENFA0018.pdf" (at 165.1 205.74 0)
      (effects (font (size 1.27 1.27) (thickness 0.15)) (justify left bottom) hide)
    )
    (property "MPN" "BLM15PD121SN1D" (at 165.1 200.66 0)
      (effects (font (size 1.27 1.27) (thickness 0.15)) (justify left bottom) hide)
    )
    (property "Manufacturer" "Murata" (at 165.1 185.42 0)
      (effects (font (size 1.27 1.27) (thickness 0.15)) (justify left bottom) hide)
    )
    (property "Author" "Antmicro" (at 173.99 228.6 0)
      (effects (font (size 1.27 1.27) (thickness 0.15)) (justify left bottom) hide)
    )
    (property "License" "Apache-2.0" (at 173.99 231.14 0)
      (effects (font (size 1.27 1.27) (thickness 0.15)) (justify left bottom) hide)
    )
    (pin "1")
    (pin "2")
    (instances
      (project "kria-k26-devboard"
        (path ""
          (reference "FB2") (unit 1)
        )
      )
    )
  )

  (symbol (lib_id "kria-k26-devboard:FB_120Z_1.3A_Murata-BLM15PD_0402") (at 160.02 196.85 0) (unit 1)
    (in_bom yes) (on_board yes) (dnp no)
    (property "Reference" "FB1" (at 162.56 190.5 0)
      (effects (font (size 1.524 1.524)))
    )
    (property "Value" "FB_120Z_1.3A_0402" (at 162.5219 193.04 0)
      (effects (font (size 1.27 1.27) (thickness 0.15)))
    )
    (property "Footprint" "kria-k26-devboard-footprints:FB_0402_1005Metric" (at 165.1 191.77 0)
      (effects (font (size 1.27 1.27) (thickness 0.15)) (justify left bottom) hide)
    )
    (property "Datasheet" "https://www.murata.com/en-us/products/productdata/8796740059166/ENFA0018.pdf" (at 165.1 189.23 0)
      (effects (font (size 1.27 1.27) (thickness 0.15)) (justify left bottom) hide)
    )
    (property "MPN" "BLM15PD121SN1D" (at 165.1 184.15 0)
      (effects (font (size 1.27 1.27) (thickness 0.15)) (justify left bottom) hide)
    )
    (property "Manufacturer" "Murata" (at 165.1 168.91 0)
      (effects (font (size 1.27 1.27) (thickness 0.15)) (justify left bottom) hide)
    )
    (property "Author" "Antmicro" (at 173.99 212.09 0)
      (effects (font (size 1.27 1.27) (thickness 0.15)) (justify left bottom) hide)
    )
    (property "License" "Apache-2.0" (at 173.99 214.63 0)
      (effects (font (size 1.27 1.27) (thickness 0.15)) (justify left bottom) hide)
    )
    (pin "1")
    (pin "2")
    (instances
      (project "kria-k26-devboard"
        (path ""
          (reference "FB1") (unit 1)
        )
      )
    )
  )

  (symbol (lib_id "kria-k26-devboard:Kria-K26") (at 205.105 267.97 0) (unit 1)
    (in_bom yes) (on_board yes) (dnp no) (fields_autoplaced)
    (property "Reference" "M1" (at 210.185 262.89 0)
      (effects (font (size 1.27 1.27)))
    )
    (property "Value" "XILINX-KRIA-K26" (at 210.185 265.43 0)
      (effects (font (size 1.27 1.27) (thickness 0.15)))
    )
    (property "Footprint" "kria-k26-devboard-footprints:XILINX-KRIA-K26" (at 230.505 273.05 0)
      (effects (font (size 1.27 1.27) (thickness 0.15)) (justify left bottom) hide)
    )
    (property "Datasheet" "" (at 230.505 275.59 0)
      (effects (font (size 1.27 1.27) (thickness 0.15)) (justify left bottom) hide)
    )
    (property "Manufacturer" "Xilinx" (at 230.505 278.13 0)
      (effects (font (size 1.27 1.27) (thickness 0.15)) (justify left bottom) hide)
    )
    (property "MPN" "SM-K26-XCL2GC" (at 230.505 280.67 0)
      (effects (font (size 1.27 1.27) (thickness 0.15)) (justify left bottom) hide)
    )
    (property "Description" "System-On-Modules - SOM K26C SOM" (at 230.505 283.21 0)
      (effects (font (size 1.27 1.27) (thickness 0.15)) (justify left bottom) hide)
    )
    (property "Author" "Antmicro" (at 230.505 285.75 0)
      (effects (font (size 1.27 1.27) (thickness 0.15)) (justify left bottom) hide)
    )
    (property "License" "Apache-2.0" (at 230.505 288.29 0)
      (effects (font (size 1.27 1.27) (thickness 0.15)) (justify left bottom) hide)
    )
    (instances
      (project "kria-k26-devboard"
        (path ""
          (reference "M1") (unit 1)
        )
      )
    )
  )

  (symbol (lib_id "kria-k26-devboard:C_4u7_0402") (at 304.8 223.52 270) (unit 1)
    (in_bom yes) (on_board yes) (dnp no) (fields_autoplaced)
    (property "Reference" "C127" (at 307.34 224.7963 90)
      (effects (font (size 1.524 1.524)) (justify left))
    )
    (property "Value" "C_4u7_0402" (at 300.99 223.52 0)
      (effects (font (size 1.27 1.27) (thickness 0.15)) (justify left bottom) hide)
    )
    (property "Footprint" "kria-k26-devboard-footprints:C_0402_1005Metric" (at 309.88 228.6 0)
      (effects (font (size 1.27 1.27) (thickness 0.15)) (justify left bottom) hide)
    )
    (property "Datasheet" " " (at 304.8 223.52 0)
      (effects (font (size 1.27 1.27) (thickness 0.15)) (justify left bottom) hide)
    )
    (property "Manufacturer" "Murata" (at 314.96 228.6 0)
      (effects (font (size 1.27 1.27) (thickness 0.15)) (justify left bottom) hide)
    )
    (property "MPN" "GRM155R61A475MEAAD" (at 312.42 228.6 0)
      (effects (font (size 1.27 1.27) (thickness 0.15)) (justify left bottom) hide)
    )
    (property "Val" "4u7" (at 307.34 227.9712 90)
      (effects (font (size 1.27 1.27) (thickness 0.15)) (justify left))
    )
    (property "License" "Apache-2.0" (at 281.94 243.84 0)
      (effects (font (size 1.27 1.27) (thickness 0.15)) (justify left bottom) hide)
    )
    (property "Author" "Antmicro" (at 279.4 243.84 0)
      (effects (font (size 1.27 1.27) (thickness 0.15)) (justify left bottom) hide)
    )
    (property "Voltage" "" (at 276.86 243.84 0)
      (effects (font (size 1.27 1.27)) (justify left bottom) hide)
    )
    (property "Dielectric" "" (at 274.32 243.84 0)
      (effects (font (size 1.27 1.27)) (justify left bottom) hide)
    )
    (pin "1")
    (pin "2")
    (instances
      (project "kria-k26-devboard"
        (path ""
          (reference "C127") (unit 1)
        )
      )
    )
  )

  (symbol (lib_id "kria-k26-devboard:C_100n_0402") (at 314.96 223.52 270) (unit 1)
    (in_bom yes) (on_board yes) (dnp no) (fields_autoplaced)
    (property "Reference" "C128" (at 317.5 224.7963 90)
      (effects (font (size 1.524 1.524)) (justify left))
    )
    (property "Value" "C_100n_0402" (at 311.15 223.52 0)
      (effects (font (size 1.27 1.27) (thickness 0.15)) (justify left bottom) hide)
    )
    (property "Footprint" "kria-k26-devboard-footprints:C_0402_1005Metric" (at 320.04 228.6 0)
      (effects (font (size 1.27 1.27) (thickness 0.15)) (justify left bottom) hide)
    )
    (property "Datasheet" "https://search.murata.co.jp/Ceramy/image/img/A01X/G101/ENG/GRM155R61H104KE14-01.pdf" (at 314.96 223.52 0)
      (effects (font (size 1.27 1.27) (thickness 0.15)) (justify left bottom) hide)
    )
    (property "Manufacturer" "Murata" (at 325.12 228.6 0)
      (effects (font (size 1.27 1.27) (thickness 0.15)) (justify left bottom) hide)
    )
    (property "MPN" "GRM155R61H104KE14D" (at 322.58 228.6 0)
      (effects (font (size 1.27 1.27) (thickness 0.15)) (justify left bottom) hide)
    )
    (property "Val" "100n" (at 317.5 227.9712 90)
      (effects (font (size 1.27 1.27) (thickness 0.15)) (justify left))
    )
    (property "License" "Apache-2.0" (at 292.1 243.84 0)
      (effects (font (size 1.27 1.27) (thickness 0.15)) (justify left bottom) hide)
    )
    (property "Author" "Antmicro" (at 289.56 243.84 0)
      (effects (font (size 1.27 1.27) (thickness 0.15)) (justify left bottom) hide)
    )
    (property "Voltage" "50V" (at 287.02 243.84 0)
      (effects (font (size 1.27 1.27)) (justify left bottom) hide)
    )
    (property "Dielectric" "X5R" (at 284.48 243.84 0)
      (effects (font (size 1.27 1.27)) (justify left bottom) hide)
    )
    (pin "1")
    (pin "2")
    (instances
      (project "kria-k26-devboard"
        (path ""
          (reference "C128") (unit 1)
        )
      )
    )
  )

  (symbol (lib_id "kria-k26-devboard:PinHeader_1x2_P2.54mm_Drill1.02mm") (at 170.815 205.74 0) (mirror x) (unit 1)
    (in_bom yes) (on_board yes) (dnp no) (fields_autoplaced)
    (property "Reference" "J6" (at 177.165 203.1999 0)
      (effects (font (size 1.27 1.27)) (justify left))
    )
    (property "Value" "PinHeader_1x2_P2.54mm_Drill1.02mm" (at 174.625 198.755 0)
      (effects (font (size 1.27 1.27) (thickness 0.15)) hide)
    )
    (property "Footprint" "kria-k26-devboard-footprints:PinHeader_1x2_P2.54mm_Drill1.02mm" (at 175.895 210.82 0)
      (effects (font (size 1.27 1.27) (thickness 0.15)) (justify left bottom) hide)
    )
    (property "Datasheet" "https://www.mouser.pl/datasheet/2/181/M20-999-1218971.pdf" (at 175.895 213.36 0)
      (effects (font (size 1.27 1.27) (thickness 0.15)) (justify left bottom) hide)
    )
    (property "MPN" "M20-9990246" (at 177.165 205.7399 0)
      (effects (font (size 1.27 1.27) (thickness 0.15)) (justify left))
    )
    (property "Manufacturer" "Harwin" (at 175.895 233.68 0)
      (effects (font (size 1.27 1.27) (thickness 0.15)) (justify left bottom) hide)
    )
    (property "Author" "Antmicro" (at 191.135 185.42 0)
      (effects (font (size 1.27 1.27) (thickness 0.15)) (justify left bottom) hide)
    )
    (property "License" "Apache-2.0" (at 191.135 182.88 0)
      (effects (font (size 1.27 1.27) (thickness 0.15)) (justify left bottom) hide)
    )
    (pin "1")
    (pin "2")
    (instances
      (project "kria-k26-devboard"
        (path ""
          (reference "J6") (unit 1)
        )
      )
    )
  )

  (symbol (lib_id "kria-k26-devboard:C_100n_0402") (at 326.39 223.52 270) (unit 1)
    (in_bom yes) (on_board yes) (dnp no) (fields_autoplaced)
    (property "Reference" "C129" (at 328.93 224.7963 90)
      (effects (font (size 1.524 1.524)) (justify left))
    )
    (property "Value" "C_100n_0402" (at 322.58 223.52 0)
      (effects (font (size 1.27 1.27) (thickness 0.15)) (justify left bottom) hide)
    )
    (property "Footprint" "kria-k26-devboard-footprints:C_0402_1005Metric" (at 331.47 228.6 0)
      (effects (font (size 1.27 1.27) (thickness 0.15)) (justify left bottom) hide)
    )
    (property "Datasheet" "https://search.murata.co.jp/Ceramy/image/img/A01X/G101/ENG/GRM155R61H104KE14-01.pdf" (at 326.39 223.52 0)
      (effects (font (size 1.27 1.27) (thickness 0.15)) (justify left bottom) hide)
    )
    (property "Manufacturer" "Murata" (at 336.55 228.6 0)
      (effects (font (size 1.27 1.27) (thickness 0.15)) (justify left bottom) hide)
    )
    (property "MPN" "GRM155R61H104KE14D" (at 334.01 228.6 0)
      (effects (font (size 1.27 1.27) (thickness 0.15)) (justify left bottom) hide)
    )
    (property "Val" "100n" (at 328.93 227.9712 90)
      (effects (font (size 1.27 1.27) (thickness 0.15)) (justify left))
    )
    (property "License" "Apache-2.0" (at 303.53 243.84 0)
      (effects (font (size 1.27 1.27) (thickness 0.15)) (justify left bottom) hide)
    )
    (property "Author" "Antmicro" (at 300.99 243.84 0)
      (effects (font (size 1.27 1.27) (thickness 0.15)) (justify left bottom) hide)
    )
    (property "Voltage" "50V" (at 298.45 243.84 0)
      (effects (font (size 1.27 1.27)) (justify left bottom) hide)
    )
    (property "Dielectric" "X5R" (at 295.91 243.84 0)
      (effects (font (size 1.27 1.27)) (justify left bottom) hide)
    )
    (pin "1")
    (pin "2")
    (instances
      (project "kria-k26-devboard"
        (path ""
          (reference "C129") (unit 1)
        )
      )
    )
  )

  (symbol (lib_id "kria-k26-devboard:GND") (at 326.39 228.6 0) (unit 1)
    (in_bom yes) (on_board yes) (dnp no) (fields_autoplaced)
    (property "Reference" "#PWR0188" (at 326.39 234.95 0)
      (effects (font (size 1.27 1.27)) hide)
    )
    (property "Value" "GND" (at 326.39 233.172 0)
      (effects (font (size 1.27 1.27)))
    )
    (property "Footprint" "" (at 335.28 236.22 0)
      (effects (font (size 1.27 1.27) (thickness 0.15)) (justify left bottom) hide)
    )
    (property "Datasheet" "" (at 335.28 241.3 0)
      (effects (font (size 1.27 1.27) (thickness 0.15)) (justify left bottom) hide)
    )
    (property "Author" "Antmicro" (at 335.28 236.22 0)
      (effects (font (size 1.27 1.27) (thickness 0.15)) (justify left bottom) hide)
    )
    (property "License" "Apache-2.0" (at 335.28 238.76 0)
      (effects (font (size 1.27 1.27) (thickness 0.15)) (justify left bottom) hide)
    )
    (pin "1")
    (instances
      (project "kria-k26-devboard"
        (path ""
          (reference "#PWR0188") (unit 1)
        )
      )
    )
  )

  (symbol (lib_id "kria-k26-devboard:R_470R_0402") (at 32.385 203.2 270) (unit 1)
    (in_bom yes) (on_board yes) (dnp no) (fields_autoplaced)
    (property "Reference" "R79" (at 34.417 204.47 90)
      (effects (font (size 1.524 1.524)) (justify left))
    )
    (property "Value" "R_470R_0402" (at 28.575 203.2 0)
      (effects (font (size 1.27 1.27) (thickness 0.15)) (justify left bottom) hide)
    )
    (property "Footprint" "kria-k26-devboard-footprints:R_0402_1005Metric" (at 37.465 208.28 0)
      (effects (font (size 1.27 1.27) (thickness 0.15)) (justify left bottom) hide)
    )
    (property "Datasheet" "https://www.bourns.com/docs/product-datasheets/cr.pdf" (at 32.385 203.2 0)
      (effects (font (size 1.27 1.27) (thickness 0.15)) (justify left bottom) hide)
    )
    (property "Manufacturer" "Bourns" (at 42.545 208.28 0)
      (effects (font (size 1.27 1.27) (thickness 0.15)) (justify left bottom) hide)
    )
    (property "MPN" "CR0402-FX-4700GLF" (at 40.005 208.28 0)
      (effects (font (size 1.27 1.27) (thickness 0.15)) (justify left bottom) hide)
    )
    (property "Val" "470R" (at 34.417 207.6449 90)
      (effects (font (size 1.27 1.27) (thickness 0.15)) (justify left))
    )
    (property "License" "Apache-2.0" (at 6.985 223.52 0)
      (effects (font (size 1.27 1.27) (thickness 0.15)) (justify left bottom) hide)
    )
    (property "Author" "Antmicro" (at 4.445 223.52 0)
      (effects (font (size 1.27 1.27) (thickness 0.15)) (justify left bottom) hide)
    )
    (property "Tolerance" "1%" (at 22.225 223.52 0)
      (effects (font (size 1.27 1.27)) (justify left bottom) hide)
    )
    (pin "1")
    (pin "2")
    (instances
      (project "kria-k26-devboard"
        (path ""
          (reference "R79") (unit 1)
        )
      )
    )
  )

  (symbol (lib_id "kria-k26-devboard:R_470R_0402") (at 41.275 203.2 270) (unit 1)
    (in_bom yes) (on_board yes) (dnp no) (fields_autoplaced)
    (property "Reference" "R80" (at 43.307 204.47 90)
      (effects (font (size 1.524 1.524)) (justify left))
    )
    (property "Value" "R_470R_0402" (at 37.465 203.2 0)
      (effects (font (size 1.27 1.27) (thickness 0.15)) (justify left bottom) hide)
    )
    (property "Footprint" "kria-k26-devboard-footprints:R_0402_1005Metric" (at 46.355 208.28 0)
      (effects (font (size 1.27 1.27) (thickness 0.15)) (justify left bottom) hide)
    )
    (property "Datasheet" "https://www.bourns.com/docs/product-datasheets/cr.pdf" (at 41.275 203.2 0)
      (effects (font (size 1.27 1.27) (thickness 0.15)) (justify left bottom) hide)
    )
    (property "Manufacturer" "Bourns" (at 51.435 208.28 0)
      (effects (font (size 1.27 1.27) (thickness 0.15)) (justify left bottom) hide)
    )
    (property "MPN" "CR0402-FX-4700GLF" (at 48.895 208.28 0)
      (effects (font (size 1.27 1.27) (thickness 0.15)) (justify left bottom) hide)
    )
    (property "Val" "470R" (at 43.307 207.6449 90)
      (effects (font (size 1.27 1.27) (thickness 0.15)) (justify left))
    )
    (property "License" "Apache-2.0" (at 15.875 223.52 0)
      (effects (font (size 1.27 1.27) (thickness 0.15)) (justify left bottom) hide)
    )
    (property "Author" "Antmicro" (at 13.335 223.52 0)
      (effects (font (size 1.27 1.27) (thickness 0.15)) (justify left bottom) hide)
    )
    (property "Tolerance" "1%" (at 31.115 223.52 0)
      (effects (font (size 1.27 1.27)) (justify left bottom) hide)
    )
    (pin "1")
    (pin "2")
    (instances
      (project "kria-k26-devboard"
        (path ""
          (reference "R80") (unit 1)
        )
      )
    )
  )

  (symbol (lib_id "kria-k26-devboard:R_470R_0402") (at 50.165 203.2 270) (unit 1)
    (in_bom no) (on_board yes) (dnp yes)
    (property "Reference" "R81" (at 52.197 204.47 90)
      (effects (font (size 1.524 1.524)) (justify left))
    )
    (property "Value" "R_470R_0402" (at 46.355 203.2 0)
      (effects (font (size 1.27 1.27) (thickness 0.15)) (justify left bottom) hide)
    )
    (property "Footprint" "kria-k26-devboard-footprints:R_0402_1005Metric" (at 55.245 208.28 0)
      (effects (font (size 1.27 1.27) (thickness 0.15)) (justify left bottom) hide)
    )
    (property "Datasheet" "https://www.bourns.com/docs/product-datasheets/cr.pdf" (at 50.165 203.2 0)
      (effects (font (size 1.27 1.27) (thickness 0.15)) (justify left bottom) hide)
    )
    (property "Manufacturer" "Bourns" (at 60.325 208.28 0)
      (effects (font (size 1.27 1.27) (thickness 0.15)) (justify left bottom) hide)
    )
    (property "MPN" "CR0402-FX-4700GLF" (at 57.785 208.28 0)
      (effects (font (size 1.27 1.27) (thickness 0.15)) (justify left bottom) hide)
    )
    (property "Val" "470R" (at 52.197 207.6449 90)
      (effects (font (size 1.27 1.27) (thickness 0.15)) (justify left))
    )
    (property "License" "Apache-2.0" (at 24.765 223.52 0)
      (effects (font (size 1.27 1.27) (thickness 0.15)) (justify left bottom) hide)
    )
    (property "Author" "Antmicro" (at 22.225 223.52 0)
      (effects (font (size 1.27 1.27) (thickness 0.15)) (justify left bottom) hide)
    )
    (property "Tolerance" "1%" (at 40.005 223.52 0)
      (effects (font (size 1.27 1.27)) (justify left bottom) hide)
    )
    (property "DNP" "DNP" (at 50.165 205.74 0)
      (effects (font (size 1.27 1.27)))
    )
    (pin "1")
    (pin "2")
    (instances
      (project "kria-k26-devboard"
        (path ""
          (reference "R81") (unit 1)
        )
      )
    )
  )

  (symbol (lib_id "kria-k26-devboard:R_470R_0402") (at 59.055 203.2 270) (unit 1)
    (in_bom yes) (on_board yes) (dnp no) (fields_autoplaced)
    (property "Reference" "R82" (at 61.087 204.47 90)
      (effects (font (size 1.524 1.524)) (justify left))
    )
    (property "Value" "R_470R_0402" (at 55.245 203.2 0)
      (effects (font (size 1.27 1.27) (thickness 0.15)) (justify left bottom) hide)
    )
    (property "Footprint" "kria-k26-devboard-footprints:R_0402_1005Metric" (at 64.135 208.28 0)
      (effects (font (size 1.27 1.27) (thickness 0.15)) (justify left bottom) hide)
    )
    (property "Datasheet" "https://www.bourns.com/docs/product-datasheets/cr.pdf" (at 59.055 203.2 0)
      (effects (font (size 1.27 1.27) (thickness 0.15)) (justify left bottom) hide)
    )
    (property "Manufacturer" "Bourns" (at 69.215 208.28 0)
      (effects (font (size 1.27 1.27) (thickness 0.15)) (justify left bottom) hide)
    )
    (property "MPN" "CR0402-FX-4700GLF" (at 66.675 208.28 0)
      (effects (font (size 1.27 1.27) (thickness 0.15)) (justify left bottom) hide)
    )
    (property "Val" "470R" (at 61.087 207.6449 90)
      (effects (font (size 1.27 1.27) (thickness 0.15)) (justify left))
    )
    (property "License" "Apache-2.0" (at 33.655 223.52 0)
      (effects (font (size 1.27 1.27) (thickness 0.15)) (justify left bottom) hide)
    )
    (property "Author" "Antmicro" (at 31.115 223.52 0)
      (effects (font (size 1.27 1.27) (thickness 0.15)) (justify left bottom) hide)
    )
    (property "Tolerance" "1%" (at 48.895 223.52 0)
      (effects (font (size 1.27 1.27)) (justify left bottom) hide)
    )
    (pin "1")
    (pin "2")
    (instances
      (project "kria-k26-devboard"
        (path ""
          (reference "R82") (unit 1)
        )
      )
    )
  )

  (symbol (lib_id "kria-k26-devboard:GND") (at 59.055 214.63 0) (unit 1)
    (in_bom yes) (on_board yes) (dnp no) (fields_autoplaced)
    (property "Reference" "#PWR0145" (at 59.055 220.98 0)
      (effects (font (size 1.27 1.27)) hide)
    )
    (property "Value" "GND" (at 59.055 219.202 0)
      (effects (font (size 1.27 1.27)))
    )
    (property "Footprint" "" (at 67.945 222.25 0)
      (effects (font (size 1.27 1.27) (thickness 0.15)) (justify left bottom) hide)
    )
    (property "Datasheet" "" (at 67.945 227.33 0)
      (effects (font (size 1.27 1.27) (thickness 0.15)) (justify left bottom) hide)
    )
    (property "Author" "Antmicro" (at 67.945 222.25 0)
      (effects (font (size 1.27 1.27) (thickness 0.15)) (justify left bottom) hide)
    )
    (property "License" "Apache-2.0" (at 67.945 224.79 0)
      (effects (font (size 1.27 1.27) (thickness 0.15)) (justify left bottom) hide)
    )
    (pin "1")
    (instances
      (project "kria-k26-devboard"
        (path ""
          (reference "#PWR0145") (unit 1)
        )
      )
    )
  )

  (symbol (lib_id "kria-k26-devboard:MP_Pad6mm_Drill3mm") (at 151.765 260.985 180) (unit 1)
    (in_bom no) (on_board yes) (dnp no) (fields_autoplaced)
    (property "Reference" "MP1" (at 146.685 254 0)
      (effects (font (size 1.27 1.27)))
    )
    (property "Value" "MP_Pad6mm_Drill3mm" (at 146.685 256.54 0)
      (effects (font (size 1.27 1.27) (thickness 0.15)))
    )
    (property "Footprint" "kria-k26-devboard-footprints:MP_Pad6mm_Drill3mm" (at 131.445 253.365 0)
      (effects (font (size 1.27 1.27) (thickness 0.15)) (justify left bottom) hide)
    )
    (property "Datasheet" "" (at 134.925 245.415 0)
      (effects (font (size 1.27 1.27) (thickness 0.15)) (justify left bottom) hide)
    )
    (property "MPN" "" (at 151.765 260.985 0)
      (effects (font (size 1.27 1.27)) hide)
    )
    (property "Manufacturer" "" (at 151.765 260.985 0)
      (effects (font (size 1.27 1.27)) hide)
    )
    (property "Author" "Antmicro" (at 131.445 250.825 0)
      (effects (font (size 1.27 1.27) (thickness 0.15)) (justify left bottom) hide)
    )
    (property "License" "Apache-2.0" (at 131.445 248.285 0)
      (effects (font (size 1.27 1.27) (thickness 0.15)) (justify left bottom) hide)
    )
    (pin "1")
    (instances
      (project "kria-k26-devboard"
        (path ""
          (reference "MP1") (unit 1)
        )
      )
    )
  )

  (symbol (lib_id "kria-k26-devboard:MP_Pad6mm_Drill3mm") (at 184.785 260.985 180) (unit 1)
    (in_bom no) (on_board yes) (dnp no) (fields_autoplaced)
    (property "Reference" "MP2" (at 179.705 254 0)
      (effects (font (size 1.27 1.27)))
    )
    (property "Value" "MP_Pad6mm_Drill3mm" (at 179.705 256.54 0)
      (effects (font (size 1.27 1.27) (thickness 0.15)))
    )
    (property "Footprint" "kria-k26-devboard-footprints:MP_Pad6mm_Drill3mm" (at 164.465 253.365 0)
      (effects (font (size 1.27 1.27) (thickness 0.15)) (justify left bottom) hide)
    )
    (property "Datasheet" "" (at 167.945 245.415 0)
      (effects (font (size 1.27 1.27) (thickness 0.15)) (justify left bottom) hide)
    )
    (property "MPN" "" (at 184.785 260.985 0)
      (effects (font (size 1.27 1.27)) hide)
    )
    (property "Manufacturer" "" (at 184.785 260.985 0)
      (effects (font (size 1.27 1.27)) hide)
    )
    (property "Author" "Antmicro" (at 164.465 250.825 0)
      (effects (font (size 1.27 1.27) (thickness 0.15)) (justify left bottom) hide)
    )
    (property "License" "Apache-2.0" (at 164.465 248.285 0)
      (effects (font (size 1.27 1.27) (thickness 0.15)) (justify left bottom) hide)
    )
    (pin "1")
    (instances
      (project "kria-k26-devboard"
        (path ""
          (reference "MP2") (unit 1)
        )
      )
    )
  )

  (symbol (lib_id "kria-k26-devboard:MP_Pad6mm_Drill3mm") (at 184.785 276.86 180) (unit 1)
    (in_bom no) (on_board yes) (dnp no) (fields_autoplaced)
    (property "Reference" "MP4" (at 179.705 269.24 0)
      (effects (font (size 1.27 1.27)))
    )
    (property "Value" "MP_Pad6mm_Drill3mm" (at 179.705 271.78 0)
      (effects (font (size 1.27 1.27) (thickness 0.15)))
    )
    (property "Footprint" "kria-k26-devboard-footprints:MP_Pad6mm_Drill3mm" (at 164.465 269.24 0)
      (effects (font (size 1.27 1.27) (thickness 0.15)) (justify left bottom) hide)
    )
    (property "Datasheet" "" (at 167.945 261.29 0)
      (effects (font (size 1.27 1.27) (thickness 0.15)) (justify left bottom) hide)
    )
    (property "MPN" "" (at 184.785 276.86 0)
      (effects (font (size 1.27 1.27)) hide)
    )
    (property "Manufacturer" "" (at 184.785 276.86 0)
      (effects (font (size 1.27 1.27)) hide)
    )
    (property "Author" "Antmicro" (at 164.465 266.7 0)
      (effects (font (size 1.27 1.27) (thickness 0.15)) (justify left bottom) hide)
    )
    (property "License" "Apache-2.0" (at 164.465 264.16 0)
      (effects (font (size 1.27 1.27) (thickness 0.15)) (justify left bottom) hide)
    )
    (pin "1")
    (instances
      (project "kria-k26-devboard"
        (path ""
          (reference "MP4") (unit 1)
        )
      )
    )
  )

  (symbol (lib_id "kria-k26-devboard:MP_Pad6mm_Drill3mm") (at 151.765 276.86 180) (unit 1)
    (in_bom no) (on_board yes) (dnp no) (fields_autoplaced)
    (property "Reference" "MP3" (at 146.685 269.24 0)
      (effects (font (size 1.27 1.27)))
    )
    (property "Value" "MP_Pad6mm_Drill3mm" (at 146.685 271.78 0)
      (effects (font (size 1.27 1.27) (thickness 0.15)))
    )
    (property "Footprint" "kria-k26-devboard-footprints:MP_Pad6mm_Drill3mm" (at 131.445 269.24 0)
      (effects (font (size 1.27 1.27) (thickness 0.15)) (justify left bottom) hide)
    )
    (property "Datasheet" "" (at 134.925 261.29 0)
      (effects (font (size 1.27 1.27) (thickness 0.15)) (justify left bottom) hide)
    )
    (property "MPN" "" (at 151.765 276.86 0)
      (effects (font (size 1.27 1.27)) hide)
    )
    (property "Manufacturer" "" (at 151.765 276.86 0)
      (effects (font (size 1.27 1.27)) hide)
    )
    (property "Author" "Antmicro" (at 131.445 266.7 0)
      (effects (font (size 1.27 1.27) (thickness 0.15)) (justify left bottom) hide)
    )
    (property "License" "Apache-2.0" (at 131.445 264.16 0)
      (effects (font (size 1.27 1.27) (thickness 0.15)) (justify left bottom) hide)
    )
    (pin "1")
    (instances
      (project "kria-k26-devboard"
        (path ""
          (reference "MP3") (unit 1)
        )
      )
    )
  )

  (symbol (lib_id "kria-k26-devboard:GND") (at 153.035 260.985 90) (unit 1)
    (in_bom yes) (on_board yes) (dnp no) (fields_autoplaced)
    (property "Reference" "#PWR0208" (at 159.385 260.985 0)
      (effects (font (size 1.27 1.27)) hide)
    )
    (property "Value" "GND" (at 156.845 260.9849 90)
      (effects (font (size 1.27 1.27)) (justify right))
    )
    (property "Footprint" "" (at 160.655 252.095 0)
      (effects (font (size 1.27 1.27) (thickness 0.15)) (justify left bottom) hide)
    )
    (property "Datasheet" "" (at 165.735 252.095 0)
      (effects (font (size 1.27 1.27) (thickness 0.15)) (justify left bottom) hide)
    )
    (property "Author" "Antmicro" (at 160.655 252.095 0)
      (effects (font (size 1.27 1.27) (thickness 0.15)) (justify left bottom) hide)
    )
    (property "License" "Apache-2.0" (at 163.195 252.095 0)
      (effects (font (size 1.27 1.27) (thickness 0.15)) (justify left bottom) hide)
    )
    (pin "1")
    (instances
      (project "kria-k26-devboard"
        (path ""
          (reference "#PWR0208") (unit 1)
        )
      )
    )
  )

  (symbol (lib_id "kria-k26-devboard:GND") (at 186.055 260.985 90) (unit 1)
    (in_bom yes) (on_board yes) (dnp no) (fields_autoplaced)
    (property "Reference" "#PWR0209" (at 192.405 260.985 0)
      (effects (font (size 1.27 1.27)) hide)
    )
    (property "Value" "GND" (at 189.865 260.9849 90)
      (effects (font (size 1.27 1.27)) (justify right))
    )
    (property "Footprint" "" (at 193.675 252.095 0)
      (effects (font (size 1.27 1.27) (thickness 0.15)) (justify left bottom) hide)
    )
    (property "Datasheet" "" (at 198.755 252.095 0)
      (effects (font (size 1.27 1.27) (thickness 0.15)) (justify left bottom) hide)
    )
    (property "Author" "Antmicro" (at 193.675 252.095 0)
      (effects (font (size 1.27 1.27) (thickness 0.15)) (justify left bottom) hide)
    )
    (property "License" "Apache-2.0" (at 196.215 252.095 0)
      (effects (font (size 1.27 1.27) (thickness 0.15)) (justify left bottom) hide)
    )
    (pin "1")
    (instances
      (project "kria-k26-devboard"
        (path ""
          (reference "#PWR0209") (unit 1)
        )
      )
    )
  )

  (symbol (lib_id "kria-k26-devboard:GND") (at 153.035 276.86 90) (unit 1)
    (in_bom yes) (on_board yes) (dnp no) (fields_autoplaced)
    (property "Reference" "#PWR0231" (at 159.385 276.86 0)
      (effects (font (size 1.27 1.27)) hide)
    )
    (property "Value" "GND" (at 156.21 276.8599 90)
      (effects (font (size 1.27 1.27)) (justify right))
    )
    (property "Footprint" "" (at 160.655 267.97 0)
      (effects (font (size 1.27 1.27) (thickness 0.15)) (justify left bottom) hide)
    )
    (property "Datasheet" "" (at 165.735 267.97 0)
      (effects (font (size 1.27 1.27) (thickness 0.15)) (justify left bottom) hide)
    )
    (property "Author" "Antmicro" (at 160.655 267.97 0)
      (effects (font (size 1.27 1.27) (thickness 0.15)) (justify left bottom) hide)
    )
    (property "License" "Apache-2.0" (at 163.195 267.97 0)
      (effects (font (size 1.27 1.27) (thickness 0.15)) (justify left bottom) hide)
    )
    (pin "1")
    (instances
      (project "kria-k26-devboard"
        (path ""
          (reference "#PWR0231") (unit 1)
        )
      )
    )
  )

  (symbol (lib_id "kria-k26-devboard:GND") (at 186.055 276.86 90) (unit 1)
    (in_bom yes) (on_board yes) (dnp no) (fields_autoplaced)
    (property "Reference" "#PWR0232" (at 192.405 276.86 0)
      (effects (font (size 1.27 1.27)) hide)
    )
    (property "Value" "GND" (at 189.23 276.8599 90)
      (effects (font (size 1.27 1.27)) (justify right))
    )
    (property "Footprint" "" (at 193.675 267.97 0)
      (effects (font (size 1.27 1.27) (thickness 0.15)) (justify left bottom) hide)
    )
    (property "Datasheet" "" (at 198.755 267.97 0)
      (effects (font (size 1.27 1.27) (thickness 0.15)) (justify left bottom) hide)
    )
    (property "Author" "Antmicro" (at 193.675 267.97 0)
      (effects (font (size 1.27 1.27) (thickness 0.15)) (justify left bottom) hide)
    )
    (property "License" "Apache-2.0" (at 196.215 267.97 0)
      (effects (font (size 1.27 1.27) (thickness 0.15)) (justify left bottom) hide)
    )
    (pin "1")
    (instances
      (project "kria-k26-devboard"
        (path ""
          (reference "#PWR0232") (unit 1)
        )
      )
    )
  )

  (symbol (lib_id "kria-k26-devboard:C_100n_0402") (at 155.575 200.66 270) (unit 1)
    (in_bom yes) (on_board yes) (dnp no)
    (property "Reference" "C253" (at 156.21 201.295 90)
      (effects (font (size 1.524 1.524)) (justify left))
    )
    (property "Value" "C_100n_0402" (at 151.765 200.66 0)
      (effects (font (size 1.27 1.27) (thickness 0.15)) (justify left bottom) hide)
    )
    (property "Footprint" "kria-k26-devboard-footprints:C_0402_1005Metric" (at 160.655 205.74 0)
      (effects (font (size 1.27 1.27) (thickness 0.15)) (justify left bottom) hide)
    )
    (property "Datasheet" "https://search.murata.co.jp/Ceramy/image/img/A01X/G101/ENG/GRM155R61H104KE14-01.pdf" (at 155.575 200.66 0)
      (effects (font (size 1.27 1.27) (thickness 0.15)) (justify left bottom) hide)
    )
    (property "Manufacturer" "Murata" (at 165.735 205.74 0)
      (effects (font (size 1.27 1.27) (thickness 0.15)) (justify left bottom) hide)
    )
    (property "MPN" "GRM155R61H104KE14D" (at 163.195 205.74 0)
      (effects (font (size 1.27 1.27) (thickness 0.15)) (justify left bottom) hide)
    )
    (property "Val" "100n" (at 156.21 205.105 90)
      (effects (font (size 1.27 1.27) (thickness 0.15)) (justify left))
    )
    (property "License" "Apache-2.0" (at 132.715 220.98 0)
      (effects (font (size 1.27 1.27) (thickness 0.15)) (justify left bottom) hide)
    )
    (property "Author" "Antmicro" (at 130.175 220.98 0)
      (effects (font (size 1.27 1.27) (thickness 0.15)) (justify left bottom) hide)
    )
    (property "Voltage" "50V" (at 127.635 220.98 0)
      (effects (font (size 1.27 1.27)) (justify left bottom) hide)
    )
    (property "Dielectric" "X5R" (at 125.095 220.98 0)
      (effects (font (size 1.27 1.27)) (justify left bottom) hide)
    )
    (pin "1")
    (pin "2")
    (instances
      (project "kria-k26-devboard"
        (path ""
          (reference "C253") (unit 1)
        )
      )
    )
  )

  (symbol (lib_id "kria-k26-devboard:GND") (at 141.605 216.535 0) (unit 1)
    (in_bom yes) (on_board yes) (dnp no) (fields_autoplaced)
    (property "Reference" "#PWR0219" (at 141.605 222.885 0)
      (effects (font (size 1.27 1.27)) hide)
    )
    (property "Value" "GND" (at 141.605 221.615 0)
      (effects (font (size 1.27 1.27)))
    )
    (property "Footprint" "" (at 150.495 224.155 0)
      (effects (font (size 1.27 1.27) (thickness 0.15)) (justify left bottom) hide)
    )
    (property "Datasheet" "" (at 150.495 229.235 0)
      (effects (font (size 1.27 1.27) (thickness 0.15)) (justify left bottom) hide)
    )
    (property "Author" "Antmicro" (at 150.495 224.155 0)
      (effects (font (size 1.27 1.27) (thickness 0.15)) (justify left bottom) hide)
    )
    (property "License" "Apache-2.0" (at 150.495 226.695 0)
      (effects (font (size 1.27 1.27) (thickness 0.15)) (justify left bottom) hide)
    )
    (pin "1")
    (instances
      (project "kria-k26-devboard"
        (path ""
          (reference "#PWR0219") (unit 1)
        )
      )
    )
  )

  (symbol (lib_id "kria-k26-devboard:R_0R_0402") (at 88.265 224.155 90) (unit 1)
    (in_bom no) (on_board yes) (dnp yes)
    (property "Reference" "R178" (at 86.36 219.71 90)
      (effects (font (size 1.524 1.524)) (justify left))
    )
    (property "Value" "R_0R_0402" (at 92.075 224.155 0)
      (effects (font (size 1.27 1.27) (thickness 0.15)) (justify left bottom) hide)
    )
    (property "Footprint" "kria-k26-devboard-footprints:R_0402_1005Metric" (at 83.185 219.075 0)
      (effects (font (size 1.27 1.27) (thickness 0.15)) (justify left bottom) hide)
    )
    (property "Datasheet" "https://industrial.panasonic.com/cdbs/www-data/pdf/RDA0000/AOA0000C301.pdf" (at 88.265 224.155 0)
      (effects (font (size 1.27 1.27) (thickness 0.15)) (justify left bottom) hide)
    )
    (property "Manufacturer" "Panasonic" (at 78.105 219.075 0)
      (effects (font (size 1.27 1.27) (thickness 0.15)) (justify left bottom) hide)
    )
    (property "MPN" "ERJ2GE0R00X" (at 80.645 219.075 0)
      (effects (font (size 1.27 1.27) (thickness 0.15)) (justify left bottom) hide)
    )
    (property "Val" "0R" (at 86.36 222.25 90)
      (effects (font (size 1.27 1.27) (thickness 0.15)) (justify left))
    )
    (property "DNP" "DNP" (at 88.265 219.71 0)
      (effects (font (size 1.27 1.27)) (justify right))
    )
    (property "License" "Apache-2.0" (at 113.665 203.835 0)
      (effects (font (size 1.27 1.27) (thickness 0.15)) (justify left bottom) hide)
    )
    (property "Author" "Antmicro" (at 116.205 203.835 0)
      (effects (font (size 1.27 1.27) (thickness 0.15)) (justify left bottom) hide)
    )
    (property "Tolerance" "~" (at 98.425 203.835 0)
      (effects (font (size 1.27 1.27)) (justify left bottom) hide)
    )
    (property "Current" "1A" (at 118.745 203.835 0)
      (effects (font (size 1.27 1.27) (thickness 0.15)) (justify left bottom) hide)
    )
    (pin "1")
    (pin "2")
    (instances
      (project "kria-k26-devboard"
        (path ""
          (reference "R178") (unit 1)
        )
      )
    )
  )

  (symbol (lib_id "kria-k26-devboard:GND") (at 267.97 228.6 0) (unit 1)
    (in_bom yes) (on_board yes) (dnp no) (fields_autoplaced)
    (property "Reference" "#PWR0221" (at 267.97 234.95 0)
      (effects (font (size 1.27 1.27)) hide)
    )
    (property "Value" "GND" (at 267.97 233.68 0)
      (effects (font (size 1.27 1.27)))
    )
    (property "Footprint" "" (at 276.86 236.22 0)
      (effects (font (size 1.27 1.27) (thickness 0.15)) (justify left bottom) hide)
    )
    (property "Datasheet" "" (at 276.86 241.3 0)
      (effects (font (size 1.27 1.27) (thickness 0.15)) (justify left bottom) hide)
    )
    (property "Author" "Antmicro" (at 276.86 236.22 0)
      (effects (font (size 1.27 1.27) (thickness 0.15)) (justify left bottom) hide)
    )
    (property "License" "Apache-2.0" (at 276.86 238.76 0)
      (effects (font (size 1.27 1.27) (thickness 0.15)) (justify left bottom) hide)
    )
    (pin "1")
    (instances
      (project "kria-k26-devboard"
        (path ""
          (reference "#PWR0221") (unit 1)
        )
      )
    )
  )

  (symbol (lib_id "kria-k26-devboard:Spacer_Drill4.45mm_H5mm_9774050960R") (at 120.65 253.365 180) (unit 1)
    (in_bom yes) (on_board yes) (dnp no)
    (property "Reference" "SP1" (at 110.49 252.095 0)
      (effects (font (size 1.27 1.27) (thickness 0.15)))
    )
    (property "Value" "Spacer_Drill4.45mm_H5mm_9774050960R" (at 98.425 257.81 0)
      (effects (font (size 1.27 1.27) (thickness 0.15)))
    )
    (property "Footprint" "kria-k26-devboard-footprints:Spacer_Drill4.45mm_H5mm_9774050960R" (at 97.79 245.745 0)
      (effects (font (size 1.27 1.27) (thickness 0.15)) (justify left bottom) hide)
    )
    (property "Datasheet" "https://www.we-online.com/components/products/datasheet/9774050960R.pdf" (at 97.79 243.205 0)
      (effects (font (size 1.27 1.27) (thickness 0.15)) (justify left bottom) hide)
    )
    (property "Manufacturer" "Würth Elektronik" (at 97.79 240.665 0)
      (effects (font (size 1.27 1.27) (thickness 0.15)) (justify left bottom) hide)
    )
    (property "MPN" "9774050960R" (at 97.79 238.125 0)
      (effects (font (size 1.27 1.27) (thickness 0.15)) (justify left bottom) hide)
    )
    (property "Author" "Antmicro" (at 97.79 235.585 0)
      (effects (font (size 1.27 1.27) (thickness 0.15)) (justify left bottom) hide)
    )
    (property "License" "Apache-2.0" (at 97.79 233.045 0)
      (effects (font (size 1.27 1.27) (thickness 0.15)) (justify left bottom) hide)
    )
    (pin "1")
    (instances
      (project "kria-k26-devboard"
        (path ""
          (reference "SP1") (unit 1)
        )
      )
    )
  )

  (symbol (lib_id "kria-k26-devboard:GND") (at 262.255 271.78 0) (unit 1)
    (in_bom yes) (on_board yes) (dnp no) (fields_autoplaced)
    (property "Reference" "#PWR0222" (at 262.255 278.13 0)
      (effects (font (size 1.27 1.27)) hide)
    )
    (property "Value" "GND" (at 262.255 276.225 0)
      (effects (font (size 1.27 1.27)))
    )
    (property "Footprint" "" (at 271.145 279.4 0)
      (effects (font (size 1.27 1.27) (thickness 0.15)) (justify left bottom) hide)
    )
    (property "Datasheet" "" (at 271.145 284.48 0)
      (effects (font (size 1.27 1.27) (thickness 0.15)) (justify left bottom) hide)
    )
    (property "Author" "Antmicro" (at 271.145 279.4 0)
      (effects (font (size 1.27 1.27) (thickness 0.15)) (justify left bottom) hide)
    )
    (property "License" "Apache-2.0" (at 271.145 281.94 0)
      (effects (font (size 1.27 1.27) (thickness 0.15)) (justify left bottom) hide)
    )
    (pin "1")
    (instances
      (project "kria-k26-devboard"
        (path ""
          (reference "#PWR0222") (unit 1)
        )
      )
    )
  )

  (symbol (lib_id "kria-k26-devboard:DTC014T_SOT-416") (at 88.9 230.505 0) (unit 1)
    (in_bom yes) (on_board yes) (dnp no) (fields_autoplaced)
    (property "Reference" "Q19" (at 99.06 229.2349 0)
      (effects (font (size 1.27 1.27)) (justify left))
    )
    (property "Value" "DTC014T_SOT-416" (at 99.06 231.7749 0)
      (effects (font (size 1.27 1.27) (thickness 0.15)) (justify left) hide)
    )
    (property "Footprint" "kria-k26-devboard-footprints:SOT-416" (at 93.98 238.125 0)
      (effects (font (size 1.27 1.27) (thickness 0.15)) (justify left bottom) hide)
    )
    (property "Datasheet" "https://www.rohm.com/datasheet?p=DTC014TEB&dist=Mouser&media=referral&source=mouser.com&campaign=Mouser" (at 88.9 230.505 0)
      (effects (font (size 1.27 1.27) (thickness 0.15)) (justify left bottom) hide)
    )
    (property "Manufacturer" "ROHM Semiconductor" (at 104.14 233.045 0)
      (effects (font (size 1.27 1.27) (thickness 0.15)) (justify left bottom) hide)
    )
    (property "MPN" "DTC014TEBTL" (at 99.06 231.7749 0)
      (effects (font (size 1.27 1.27) (thickness 0.15)) (justify left))
    )
    (property "Author" "Antmicro" (at 114.3 250.825 0)
      (effects (font (size 1.27 1.27) (thickness 0.15)) (justify left bottom) hide)
    )
    (property "License" "Apache-2.0" (at 114.3 253.365 0)
      (effects (font (size 1.27 1.27) (thickness 0.15)) (justify left bottom) hide)
    )
    (pin "1")
    (pin "2")
    (pin "3")
    (instances
      (project "kria-k26-devboard"
        (path ""
          (reference "Q19") (unit 1)
        )
      )
    )
  )

  (symbol (lib_id "kria-k26-devboard:GND") (at 245.745 271.78 0) (unit 1)
    (in_bom yes) (on_board yes) (dnp no) (fields_autoplaced)
    (property "Reference" "#PWR0406" (at 245.745 278.13 0)
      (effects (font (size 1.27 1.27)) hide)
    )
    (property "Value" "GND" (at 245.745 276.225 0)
      (effects (font (size 1.27 1.27)))
    )
    (property "Footprint" "" (at 254.635 279.4 0)
      (effects (font (size 1.27 1.27) (thickness 0.15)) (justify left bottom) hide)
    )
    (property "Datasheet" "" (at 254.635 284.48 0)
      (effects (font (size 1.27 1.27) (thickness 0.15)) (justify left bottom) hide)
    )
    (property "Author" "Antmicro" (at 254.635 279.4 0)
      (effects (font (size 1.27 1.27) (thickness 0.15)) (justify left bottom) hide)
    )
    (property "License" "Apache-2.0" (at 254.635 281.94 0)
      (effects (font (size 1.27 1.27) (thickness 0.15)) (justify left bottom) hide)
    )
    (pin "1")
    (instances
      (project "kria-k26-devboard"
        (path ""
          (reference "#PWR0406") (unit 1)
        )
      )
    )
  )

  (symbol (lib_id "kria-k26-devboard:TP_0.75mm_SMD") (at 386.08 213.36 0) (mirror x) (unit 1)
    (in_bom yes) (on_board yes) (dnp no)
    (property "Reference" "TP57" (at 393.065 213.36 0)
      (effects (font (size 1.27 1.27)))
    )
    (property "Value" "TP_0.75mm_SMD" (at 386.08 210.82 0)
      (effects (font (size 1.27 1.27) (thickness 0.15)) (justify left bottom) hide)
    )
    (property "Footprint" "kria-k26-devboard-footprints:TP_SMD_0.75mm" (at 391.16 218.44 0)
      (effects (font (size 1.27 1.27) (thickness 0.15)) (justify left bottom) hide)
    )
    (property "Datasheet" "" (at 391.16 220.98 0)
      (effects (font (size 1.27 1.27) (thickness 0.15)) (justify left bottom) hide)
    )
    (property "MPN" "" (at 403.86 198.12 0)
      (effects (font (size 1.27 1.27) (thickness 0.15)) (justify left bottom) hide)
    )
    (property "Manufacturer" "" (at 403.86 195.58 0)
      (effects (font (size 1.27 1.27) (thickness 0.15)) (justify left bottom) hide)
    )
    (property "Author" "Antmicro" (at 403.86 193.04 0)
      (effects (font (size 1.27 1.27) (thickness 0.15)) (justify left bottom) hide)
    )
    (property "License" "Apache-2.0" (at 403.86 190.5 0)
      (effects (font (size 1.27 1.27) (thickness 0.15)) (justify left bottom) hide)
    )
    (pin "1")
    (instances
      (project "kria-k26-devboard"
        (path ""
          (reference "TP57") (unit 1)
        )
      )
    )
  )

  (symbol (lib_id "kria-k26-devboard:GND") (at 121.92 280.035 0) (unit 1)
    (in_bom yes) (on_board yes) (dnp no) (fields_autoplaced)
    (property "Reference" "#PWR0216" (at 121.92 286.385 0)
      (effects (font (size 1.27 1.27)) hide)
    )
    (property "Value" "GND" (at 124.46 281.3049 0)
      (effects (font (size 1.27 1.27)) (justify left))
    )
    (property "Footprint" "" (at 130.81 287.655 0)
      (effects (font (size 1.27 1.27) (thickness 0.15)) (justify left bottom) hide)
    )
    (property "Datasheet" "" (at 130.81 292.735 0)
      (effects (font (size 1.27 1.27) (thickness 0.15)) (justify left bottom) hide)
    )
    (property "Author" "Antmicro" (at 130.81 287.655 0)
      (effects (font (size 1.27 1.27) (thickness 0.15)) (justify left bottom) hide)
    )
    (property "License" "Apache-2.0" (at 130.81 290.195 0)
      (effects (font (size 1.27 1.27) (thickness 0.15)) (justify left bottom) hide)
    )
    (pin "1")
    (instances
      (project "kria-k26-devboard"
        (path ""
          (reference "#PWR0216") (unit 1)
        )
      )
    )
  )

  (symbol (lib_id "kria-k26-devboard:TP_0.75mm_SMD") (at 386.08 200.66 0) (mirror x) (unit 1)
    (in_bom yes) (on_board yes) (dnp no)
    (property "Reference" "TP52" (at 393.065 200.66 0)
      (effects (font (size 1.27 1.27)))
    )
    (property "Value" "TP_0.75mm_SMD" (at 386.08 198.12 0)
      (effects (font (size 1.27 1.27) (thickness 0.15)) (justify left bottom) hide)
    )
    (property "Footprint" "kria-k26-devboard-footprints:TP_SMD_0.75mm" (at 391.16 205.74 0)
      (effects (font (size 1.27 1.27) (thickness 0.15)) (justify left bottom) hide)
    )
    (property "Datasheet" "" (at 391.16 208.28 0)
      (effects (font (size 1.27 1.27) (thickness 0.15)) (justify left bottom) hide)
    )
    (property "MPN" "" (at 403.86 185.42 0)
      (effects (font (size 1.27 1.27) (thickness 0.15)) (justify left bottom) hide)
    )
    (property "Manufacturer" "" (at 403.86 182.88 0)
      (effects (font (size 1.27 1.27) (thickness 0.15)) (justify left bottom) hide)
    )
    (property "Author" "Antmicro" (at 403.86 180.34 0)
      (effects (font (size 1.27 1.27) (thickness 0.15)) (justify left bottom) hide)
    )
    (property "License" "Apache-2.0" (at 403.86 177.8 0)
      (effects (font (size 1.27 1.27) (thickness 0.15)) (justify left bottom) hide)
    )
    (pin "1")
    (instances
      (project "kria-k26-devboard"
        (path ""
          (reference "TP52") (unit 1)
        )
      )
    )
  )

  (symbol (lib_id "kria-k26-devboard:TP_0.75mm_SMD") (at 386.08 215.9 0) (mirror x) (unit 1)
    (in_bom yes) (on_board yes) (dnp no)
    (property "Reference" "TP58" (at 393.065 215.9 0)
      (effects (font (size 1.27 1.27)))
    )
    (property "Value" "TP_0.75mm_SMD" (at 386.08 213.36 0)
      (effects (font (size 1.27 1.27) (thickness 0.15)) (justify left bottom) hide)
    )
    (property "Footprint" "kria-k26-devboard-footprints:TP_SMD_0.75mm" (at 391.16 220.98 0)
      (effects (font (size 1.27 1.27) (thickness 0.15)) (justify left bottom) hide)
    )
    (property "Datasheet" "" (at 391.16 223.52 0)
      (effects (font (size 1.27 1.27) (thickness 0.15)) (justify left bottom) hide)
    )
    (property "MPN" "" (at 403.86 200.66 0)
      (effects (font (size 1.27 1.27) (thickness 0.15)) (justify left bottom) hide)
    )
    (property "Manufacturer" "" (at 403.86 198.12 0)
      (effects (font (size 1.27 1.27) (thickness 0.15)) (justify left bottom) hide)
    )
    (property "Author" "Antmicro" (at 403.86 195.58 0)
      (effects (font (size 1.27 1.27) (thickness 0.15)) (justify left bottom) hide)
    )
    (property "License" "Apache-2.0" (at 403.86 193.04 0)
      (effects (font (size 1.27 1.27) (thickness 0.15)) (justify left bottom) hide)
    )
    (pin "1")
    (instances
      (project "kria-k26-devboard"
        (path ""
          (reference "TP58") (unit 1)
        )
      )
    )
  )

  (symbol (lib_id "kria-k26-devboard:GND") (at 267.97 203.2 0) (unit 1)
    (in_bom yes) (on_board yes) (dnp no) (fields_autoplaced)
    (property "Reference" "#PWR0226" (at 267.97 209.55 0)
      (effects (font (size 1.27 1.27)) hide)
    )
    (property "Value" "GND" (at 267.97 207.645 0)
      (effects (font (size 1.27 1.27)))
    )
    (property "Footprint" "" (at 276.86 210.82 0)
      (effects (font (size 1.27 1.27) (thickness 0.15)) (justify left bottom) hide)
    )
    (property "Datasheet" "" (at 276.86 215.9 0)
      (effects (font (size 1.27 1.27) (thickness 0.15)) (justify left bottom) hide)
    )
    (property "Author" "Antmicro" (at 276.86 210.82 0)
      (effects (font (size 1.27 1.27) (thickness 0.15)) (justify left bottom) hide)
    )
    (property "License" "Apache-2.0" (at 276.86 213.36 0)
      (effects (font (size 1.27 1.27) (thickness 0.15)) (justify left bottom) hide)
    )
    (pin "1")
    (instances
      (project "kria-k26-devboard"
        (path ""
          (reference "#PWR0226") (unit 1)
        )
      )
    )
  )

  (symbol (lib_id "kria-k26-devboard:GND") (at 257.81 203.2 0) (unit 1)
    (in_bom yes) (on_board yes) (dnp no) (fields_autoplaced)
    (property "Reference" "#PWR0225" (at 257.81 209.55 0)
      (effects (font (size 1.27 1.27)) hide)
    )
    (property "Value" "GND" (at 257.81 207.645 0)
      (effects (font (size 1.27 1.27)))
    )
    (property "Footprint" "" (at 266.7 210.82 0)
      (effects (font (size 1.27 1.27) (thickness 0.15)) (justify left bottom) hide)
    )
    (property "Datasheet" "" (at 266.7 215.9 0)
      (effects (font (size 1.27 1.27) (thickness 0.15)) (justify left bottom) hide)
    )
    (property "Author" "Antmicro" (at 266.7 210.82 0)
      (effects (font (size 1.27 1.27) (thickness 0.15)) (justify left bottom) hide)
    )
    (property "License" "Apache-2.0" (at 266.7 213.36 0)
      (effects (font (size 1.27 1.27) (thickness 0.15)) (justify left bottom) hide)
    )
    (pin "1")
    (instances
      (project "kria-k26-devboard"
        (path ""
          (reference "#PWR0225") (unit 1)
        )
      )
    )
  )

  (symbol (lib_id "kria-k26-devboard:TP_0.75mm_SMD") (at 386.08 210.82 0) (mirror x) (unit 1)
    (in_bom yes) (on_board yes) (dnp no)
    (property "Reference" "TP56" (at 393.065 210.82 0)
      (effects (font (size 1.27 1.27)))
    )
    (property "Value" "TP_0.75mm_SMD" (at 386.08 208.28 0)
      (effects (font (size 1.27 1.27) (thickness 0.15)) (justify left bottom) hide)
    )
    (property "Footprint" "kria-k26-devboard-footprints:TP_SMD_0.75mm" (at 391.16 215.9 0)
      (effects (font (size 1.27 1.27) (thickness 0.15)) (justify left bottom) hide)
    )
    (property "Datasheet" "" (at 391.16 218.44 0)
      (effects (font (size 1.27 1.27) (thickness 0.15)) (justify left bottom) hide)
    )
    (property "MPN" "" (at 403.86 195.58 0)
      (effects (font (size 1.27 1.27) (thickness 0.15)) (justify left bottom) hide)
    )
    (property "Manufacturer" "" (at 403.86 193.04 0)
      (effects (font (size 1.27 1.27) (thickness 0.15)) (justify left bottom) hide)
    )
    (property "Author" "Antmicro" (at 403.86 190.5 0)
      (effects (font (size 1.27 1.27) (thickness 0.15)) (justify left bottom) hide)
    )
    (property "License" "Apache-2.0" (at 403.86 187.96 0)
      (effects (font (size 1.27 1.27) (thickness 0.15)) (justify left bottom) hide)
    )
    (pin "1")
    (instances
      (project "kria-k26-devboard"
        (path ""
          (reference "TP56") (unit 1)
        )
      )
    )
  )

  (symbol (lib_id "kria-k26-devboard:TP_0.75mm_SMD") (at 386.08 205.74 0) (mirror x) (unit 1)
    (in_bom yes) (on_board yes) (dnp no)
    (property "Reference" "TP54" (at 393.065 205.74 0)
      (effects (font (size 1.27 1.27)))
    )
    (property "Value" "TP_0.75mm_SMD" (at 386.08 203.2 0)
      (effects (font (size 1.27 1.27) (thickness 0.15)) (justify left bottom) hide)
    )
    (property "Footprint" "kria-k26-devboard-footprints:TP_SMD_0.75mm" (at 391.16 210.82 0)
      (effects (font (size 1.27 1.27) (thickness 0.15)) (justify left bottom) hide)
    )
    (property "Datasheet" "" (at 391.16 213.36 0)
      (effects (font (size 1.27 1.27) (thickness 0.15)) (justify left bottom) hide)
    )
    (property "MPN" "" (at 403.86 190.5 0)
      (effects (font (size 1.27 1.27) (thickness 0.15)) (justify left bottom) hide)
    )
    (property "Manufacturer" "" (at 403.86 187.96 0)
      (effects (font (size 1.27 1.27) (thickness 0.15)) (justify left bottom) hide)
    )
    (property "Author" "Antmicro" (at 403.86 185.42 0)
      (effects (font (size 1.27 1.27) (thickness 0.15)) (justify left bottom) hide)
    )
    (property "License" "Apache-2.0" (at 403.86 182.88 0)
      (effects (font (size 1.27 1.27) (thickness 0.15)) (justify left bottom) hide)
    )
    (pin "1")
    (instances
      (project "kria-k26-devboard"
        (path ""
          (reference "TP54") (unit 1)
        )
      )
    )
  )

  (symbol (lib_id "kria-k26-devboard:GND") (at 19.685 31.75 0) (unit 1)
    (in_bom yes) (on_board yes) (dnp no) (fields_autoplaced)
    (property "Reference" "#PWR0409" (at 19.685 38.1 0)
      (effects (font (size 1.27 1.27)) hide)
    )
    (property "Value" "GND" (at 19.685 36.83 0)
      (effects (font (size 1.27 1.27)))
    )
    (property "Footprint" "" (at 28.575 39.37 0)
      (effects (font (size 1.27 1.27) (thickness 0.15)) (justify left bottom) hide)
    )
    (property "Datasheet" "" (at 28.575 44.45 0)
      (effects (font (size 1.27 1.27) (thickness 0.15)) (justify left bottom) hide)
    )
    (property "Author" "Antmicro" (at 28.575 39.37 0)
      (effects (font (size 1.27 1.27) (thickness 0.15)) (justify left bottom) hide)
    )
    (property "License" "Apache-2.0" (at 28.575 41.91 0)
      (effects (font (size 1.27 1.27) (thickness 0.15)) (justify left bottom) hide)
    )
    (pin "1")
    (instances
      (project "kria-k26-devboard"
        (path ""
          (reference "#PWR0409") (unit 1)
        )
      )
    )
  )

  (symbol (lib_id "kria-k26-devboard:R_10k_0402") (at 88.265 199.39 270) (unit 1)
    (in_bom yes) (on_board yes) (dnp no)
    (property "Reference" "R177" (at 86.36 200.6601 90)
      (effects (font (size 1.524 1.524)) (justify right))
    )
    (property "Value" "R_10k_0402" (at 84.455 199.39 0)
      (effects (font (size 1.27 1.27) (thickness 0.15)) (justify left bottom) hide)
    )
    (property "Footprint" "kria-k26-devboard-footprints:R_0402_1005Metric" (at 93.345 204.47 0)
      (effects (font (size 1.27 1.27) (thickness 0.15)) (justify left bottom) hide)
    )
    (property "Datasheet" "https://www.bourns.com/docs/product-datasheets/cr.pdf" (at 88.265 199.39 0)
      (effects (font (size 1.27 1.27) (thickness 0.15)) (justify left bottom) hide)
    )
    (property "Manufacturer" "Bourns" (at 98.425 204.47 0)
      (effects (font (size 1.27 1.27) (thickness 0.15)) (justify left bottom) hide)
    )
    (property "MPN" "CR0402-FX-1002GLF" (at 95.885 204.47 0)
      (effects (font (size 1.27 1.27) (thickness 0.15)) (justify left bottom) hide)
    )
    (property "Val" "10k" (at 86.36 203.835 90)
      (effects (font (size 1.27 1.27) (thickness 0.15)) (justify right))
    )
    (property "License" "Apache-2.0" (at 62.865 219.71 0)
      (effects (font (size 1.27 1.27) (thickness 0.15)) (justify left bottom) hide)
    )
    (property "Author" "Antmicro" (at 60.325 219.71 0)
      (effects (font (size 1.27 1.27) (thickness 0.15)) (justify left bottom) hide)
    )
    (property "Tolerance" "1%" (at 78.105 219.71 0)
      (effects (font (size 1.27 1.27)) (justify left bottom) hide)
    )
    (pin "1")
    (pin "2")
    (instances
      (project "kria-k26-devboard"
        (path ""
          (reference "R177") (unit 1)
        )
      )
    )
  )

  (symbol (lib_id "kria-k26-devboard:GND") (at 121.92 271.145 0) (unit 1)
    (in_bom yes) (on_board yes) (dnp no) (fields_autoplaced)
    (property "Reference" "#PWR0214" (at 121.92 277.495 0)
      (effects (font (size 1.27 1.27)) hide)
    )
    (property "Value" "GND" (at 124.46 272.4149 0)
      (effects (font (size 1.27 1.27)) (justify left))
    )
    (property "Footprint" "" (at 130.81 278.765 0)
      (effects (font (size 1.27 1.27) (thickness 0.15)) (justify left bottom) hide)
    )
    (property "Datasheet" "" (at 130.81 283.845 0)
      (effects (font (size 1.27 1.27) (thickness 0.15)) (justify left bottom) hide)
    )
    (property "Author" "Antmicro" (at 130.81 278.765 0)
      (effects (font (size 1.27 1.27) (thickness 0.15)) (justify left bottom) hide)
    )
    (property "License" "Apache-2.0" (at 130.81 281.305 0)
      (effects (font (size 1.27 1.27) (thickness 0.15)) (justify left bottom) hide)
    )
    (pin "1")
    (instances
      (project "kria-k26-devboard"
        (path ""
          (reference "#PWR0214") (unit 1)
        )
      )
    )
  )

  (symbol (lib_id "kria-k26-devboard:C_100n_0402") (at 148.59 200.66 270) (unit 1)
    (in_bom yes) (on_board yes) (dnp no)
    (property "Reference" "C252" (at 148.59 201.295 90)
      (effects (font (size 1.524 1.524)) (justify left))
    )
    (property "Value" "C_100n_0402" (at 144.78 200.66 0)
      (effects (font (size 1.27 1.27) (thickness 0.15)) (justify left bottom) hide)
    )
    (property "Footprint" "kria-k26-devboard-footprints:C_0402_1005Metric" (at 153.67 205.74 0)
      (effects (font (size 1.27 1.27) (thickness 0.15)) (justify left bottom) hide)
    )
    (property "Datasheet" "https://search.murata.co.jp/Ceramy/image/img/A01X/G101/ENG/GRM155R61H104KE14-01.pdf" (at 148.59 200.66 0)
      (effects (font (size 1.27 1.27) (thickness 0.15)) (justify left bottom) hide)
    )
    (property "Manufacturer" "Murata" (at 158.75 205.74 0)
      (effects (font (size 1.27 1.27) (thickness 0.15)) (justify left bottom) hide)
    )
    (property "MPN" "GRM155R61H104KE14D" (at 156.21 205.74 0)
      (effects (font (size 1.27 1.27) (thickness 0.15)) (justify left bottom) hide)
    )
    (property "Val" "100n" (at 148.59 205.105 90)
      (effects (font (size 1.27 1.27) (thickness 0.15)) (justify left))
    )
    (property "License" "Apache-2.0" (at 125.73 220.98 0)
      (effects (font (size 1.27 1.27) (thickness 0.15)) (justify left bottom) hide)
    )
    (property "Author" "Antmicro" (at 123.19 220.98 0)
      (effects (font (size 1.27 1.27) (thickness 0.15)) (justify left bottom) hide)
    )
    (property "Voltage" "50V" (at 120.65 220.98 0)
      (effects (font (size 1.27 1.27)) (justify left bottom) hide)
    )
    (property "Dielectric" "X5R" (at 118.11 220.98 0)
      (effects (font (size 1.27 1.27)) (justify left bottom) hide)
    )
    (pin "1")
    (pin "2")
    (instances
      (project "kria-k26-devboard"
        (path ""
          (reference "C252") (unit 1)
        )
      )
    )
  )

  (symbol (lib_id "kria-k26-devboard:GND") (at 304.8 228.6 0) (unit 1)
    (in_bom yes) (on_board yes) (dnp no) (fields_autoplaced)
    (property "Reference" "#PWR0212" (at 304.8 234.95 0)
      (effects (font (size 1.27 1.27)) hide)
    )
    (property "Value" "GND" (at 304.8 233.172 0)
      (effects (font (size 1.27 1.27)))
    )
    (property "Footprint" "" (at 313.69 236.22 0)
      (effects (font (size 1.27 1.27) (thickness 0.15)) (justify left bottom) hide)
    )
    (property "Datasheet" "" (at 313.69 241.3 0)
      (effects (font (size 1.27 1.27) (thickness 0.15)) (justify left bottom) hide)
    )
    (property "Author" "Antmicro" (at 313.69 236.22 0)
      (effects (font (size 1.27 1.27) (thickness 0.15)) (justify left bottom) hide)
    )
    (property "License" "Apache-2.0" (at 313.69 238.76 0)
      (effects (font (size 1.27 1.27) (thickness 0.15)) (justify left bottom) hide)
    )
    (pin "1")
    (instances
      (project "kria-k26-devboard"
        (path ""
          (reference "#PWR0212") (unit 1)
        )
      )
    )
  )

  (symbol (lib_id "kria-k26-devboard:C_100n_0402") (at 141.605 200.66 270) (unit 1)
    (in_bom yes) (on_board yes) (dnp no)
    (property "Reference" "C251" (at 142.24 201.295 90)
      (effects (font (size 1.524 1.524)) (justify left))
    )
    (property "Value" "C_100n_0402" (at 137.795 200.66 0)
      (effects (font (size 1.27 1.27) (thickness 0.15)) (justify left bottom) hide)
    )
    (property "Footprint" "kria-k26-devboard-footprints:C_0402_1005Metric" (at 146.685 205.74 0)
      (effects (font (size 1.27 1.27) (thickness 0.15)) (justify left bottom) hide)
    )
    (property "Datasheet" "https://search.murata.co.jp/Ceramy/image/img/A01X/G101/ENG/GRM155R61H104KE14-01.pdf" (at 141.605 200.66 0)
      (effects (font (size 1.27 1.27) (thickness 0.15)) (justify left bottom) hide)
    )
    (property "Manufacturer" "Murata" (at 151.765 205.74 0)
      (effects (font (size 1.27 1.27) (thickness 0.15)) (justify left bottom) hide)
    )
    (property "MPN" "GRM155R61H104KE14D" (at 149.225 205.74 0)
      (effects (font (size 1.27 1.27) (thickness 0.15)) (justify left bottom) hide)
    )
    (property "Val" "100n" (at 142.24 205.105 90)
      (effects (font (size 1.27 1.27) (thickness 0.15)) (justify left))
    )
    (property "License" "Apache-2.0" (at 118.745 220.98 0)
      (effects (font (size 1.27 1.27) (thickness 0.15)) (justify left bottom) hide)
    )
    (property "Author" "Antmicro" (at 116.205 220.98 0)
      (effects (font (size 1.27 1.27) (thickness 0.15)) (justify left bottom) hide)
    )
    (property "Voltage" "50V" (at 113.665 220.98 0)
      (effects (font (size 1.27 1.27)) (justify left bottom) hide)
    )
    (property "Dielectric" "X5R" (at 111.125 220.98 0)
      (effects (font (size 1.27 1.27)) (justify left bottom) hide)
    )
    (pin "1")
    (pin "2")
    (instances
      (project "kria-k26-devboard"
        (path ""
          (reference "C251") (unit 1)
        )
      )
    )
  )

  (symbol (lib_id "kria-k26-devboard:GND") (at 121.92 255.905 0) (unit 1)
    (in_bom yes) (on_board yes) (dnp no) (fields_autoplaced)
    (property "Reference" "#PWR0215" (at 121.92 262.255 0)
      (effects (font (size 1.27 1.27)) hide)
    )
    (property "Value" "GND" (at 124.46 257.1749 0)
      (effects (font (size 1.27 1.27)) (justify left))
    )
    (property "Footprint" "" (at 130.81 263.525 0)
      (effects (font (size 1.27 1.27) (thickness 0.15)) (justify left bottom) hide)
    )
    (property "Datasheet" "" (at 130.81 268.605 0)
      (effects (font (size 1.27 1.27) (thickness 0.15)) (justify left bottom) hide)
    )
    (property "Author" "Antmicro" (at 130.81 263.525 0)
      (effects (font (size 1.27 1.27) (thickness 0.15)) (justify left bottom) hide)
    )
    (property "License" "Apache-2.0" (at 130.81 266.065 0)
      (effects (font (size 1.27 1.27) (thickness 0.15)) (justify left bottom) hide)
    )
    (pin "1")
    (instances
      (project "kria-k26-devboard"
        (path ""
          (reference "#PWR0215") (unit 1)
        )
      )
    )
  )

  (symbol (lib_id "kria-k26-devboard:C_100n_0402") (at 262.255 266.7 270) (unit 1)
    (in_bom yes) (on_board yes) (dnp no) (fields_autoplaced)
    (property "Reference" "C241" (at 265.43 267.9763 90)
      (effects (font (size 1.524 1.524)) (justify left))
    )
    (property "Value" "C_100n_0402" (at 258.445 266.7 0)
      (effects (font (size 1.27 1.27) (thickness 0.15)) (justify left bottom) hide)
    )
    (property "Footprint" "kria-k26-devboard-footprints:C_0402_1005Metric" (at 267.335 271.78 0)
      (effects (font (size 1.27 1.27) (thickness 0.15)) (justify left bottom) hide)
    )
    (property "Datasheet" "https://search.murata.co.jp/Ceramy/image/img/A01X/G101/ENG/GRM155R61H104KE14-01.pdf" (at 262.255 266.7 0)
      (effects (font (size 1.27 1.27) (thickness 0.15)) (justify left bottom) hide)
    )
    (property "Manufacturer" "Murata" (at 272.415 271.78 0)
      (effects (font (size 1.27 1.27) (thickness 0.15)) (justify left bottom) hide)
    )
    (property "MPN" "GRM155R61H104KE14D" (at 269.875 271.78 0)
      (effects (font (size 1.27 1.27) (thickness 0.15)) (justify left bottom) hide)
    )
    (property "Val" "100n" (at 265.43 271.1512 90)
      (effects (font (size 1.27 1.27) (thickness 0.15)) (justify left))
    )
    (property "License" "Apache-2.0" (at 239.395 287.02 0)
      (effects (font (size 1.27 1.27) (thickness 0.15)) (justify left bottom) hide)
    )
    (property "Author" "Antmicro" (at 236.855 287.02 0)
      (effects (font (size 1.27 1.27) (thickness 0.15)) (justify left bottom) hide)
    )
    (property "Voltage" "50V" (at 234.315 287.02 0)
      (effects (font (size 1.27 1.27)) (justify left bottom) hide)
    )
    (property "Dielectric" "X5R" (at 231.775 287.02 0)
      (effects (font (size 1.27 1.27)) (justify left bottom) hide)
    )
    (pin "1")
    (pin "2")
    (instances
      (project "kria-k26-devboard"
        (path ""
          (reference "C241") (unit 1)
        )
      )
    )
  )

  (symbol (lib_id "kria-k26-devboard:GND") (at 326.39 203.2 0) (unit 1)
    (in_bom yes) (on_board yes) (dnp no) (fields_autoplaced)
    (property "Reference" "#PWR0228" (at 326.39 209.55 0)
      (effects (font (size 1.27 1.27)) hide)
    )
    (property "Value" "GND" (at 326.39 208.28 0)
      (effects (font (size 1.27 1.27)))
    )
    (property "Footprint" "" (at 335.28 210.82 0)
      (effects (font (size 1.27 1.27) (thickness 0.15)) (justify left bottom) hide)
    )
    (property "Datasheet" "" (at 335.28 215.9 0)
      (effects (font (size 1.27 1.27) (thickness 0.15)) (justify left bottom) hide)
    )
    (property "Author" "Antmicro" (at 335.28 210.82 0)
      (effects (font (size 1.27 1.27) (thickness 0.15)) (justify left bottom) hide)
    )
    (property "License" "Apache-2.0" (at 335.28 213.36 0)
      (effects (font (size 1.27 1.27) (thickness 0.15)) (justify left bottom) hide)
    )
    (pin "1")
    (instances
      (project "kria-k26-devboard"
        (path ""
          (reference "#PWR0228") (unit 1)
        )
      )
    )
  )

  (symbol (lib_id "kria-k26-devboard:GND") (at 257.81 228.6 0) (unit 1)
    (in_bom yes) (on_board yes) (dnp no) (fields_autoplaced)
    (property "Reference" "#PWR0223" (at 257.81 234.95 0)
      (effects (font (size 1.27 1.27)) hide)
    )
    (property "Value" "GND" (at 257.81 233.68 0)
      (effects (font (size 1.27 1.27)))
    )
    (property "Footprint" "" (at 266.7 236.22 0)
      (effects (font (size 1.27 1.27) (thickness 0.15)) (justify left bottom) hide)
    )
    (property "Datasheet" "" (at 266.7 241.3 0)
      (effects (font (size 1.27 1.27) (thickness 0.15)) (justify left bottom) hide)
    )
    (property "Author" "Antmicro" (at 266.7 236.22 0)
      (effects (font (size 1.27 1.27) (thickness 0.15)) (justify left bottom) hide)
    )
    (property "License" "Apache-2.0" (at 266.7 238.76 0)
      (effects (font (size 1.27 1.27) (thickness 0.15)) (justify left bottom) hide)
    )
    (pin "1")
    (instances
      (project "kria-k26-devboard"
        (path ""
          (reference "#PWR0223") (unit 1)
        )
      )
    )
  )

  (symbol (lib_id "kria-k26-devboard:SW_KMR211NGLFS_SMD") (at 247.015 265.43 0) (unit 1)
    (in_bom yes) (on_board yes) (dnp no) (fields_autoplaced)
    (property "Reference" "S2" (at 252.095 257.81 0)
      (effects (font (size 1.27 1.27)))
    )
    (property "Value" "SW_SPST_KMR211NGLFS" (at 252.095 260.35 0)
      (effects (font (size 1.27 1.27) (thickness 0.15)) hide)
    )
    (property "Footprint" "kria-k26-devboard-footprints:SW_KMR211NGLFS_SMD" (at 252.095 260.35 0)
      (effects (font (size 1.27 1.27) (thickness 0.15)) (justify left bottom) hide)
    )
    (property "Datasheet" "http://www.farnell.com/datasheets/2631211.pdf" (at 252.095 257.81 0)
      (effects (font (size 1.27 1.27) (thickness 0.15)) (justify left bottom) hide)
    )
    (property "MPN" "KMR211NGLFS" (at 252.095 260.35 0)
      (effects (font (size 1.27 1.27) (thickness 0.15)))
    )
    (property "Manufacturer" "C&K" (at 252.095 253.4412 0)
      (effects (font (size 1.27 1.27) (thickness 0.15)) (justify left bottom) hide)
    )
    (property "Author" "Antmicro" (at 272.415 283.21 0)
      (effects (font (size 1.27 1.27) (thickness 0.15)) (justify left bottom) hide)
    )
    (property "License" "Apache-2.0" (at 272.415 285.75 0)
      (effects (font (size 1.27 1.27) (thickness 0.15)) (justify left bottom) hide)
    )
    (pin "1")
    (pin "2")
    (pin "3")
    (pin "4")
    (instances
      (project "kria-k26-devboard"
        (path ""
          (reference "S2") (unit 1)
        )
      )
    )
  )

  (symbol (lib_id "kria-k26-devboard:TP_0.75mm_SMD") (at 386.08 218.44 0) (mirror x) (unit 1)
    (in_bom yes) (on_board yes) (dnp no)
    (property "Reference" "TP59" (at 393.065 218.44 0)
      (effects (font (size 1.27 1.27)))
    )
    (property "Value" "TP_0.75mm_SMD" (at 386.08 215.9 0)
      (effects (font (size 1.27 1.27) (thickness 0.15)) (justify left bottom) hide)
    )
    (property "Footprint" "kria-k26-devboard-footprints:TP_SMD_0.75mm" (at 391.16 223.52 0)
      (effects (font (size 1.27 1.27) (thickness 0.15)) (justify left bottom) hide)
    )
    (property "Datasheet" "" (at 391.16 226.06 0)
      (effects (font (size 1.27 1.27) (thickness 0.15)) (justify left bottom) hide)
    )
    (property "MPN" "" (at 403.86 203.2 0)
      (effects (font (size 1.27 1.27) (thickness 0.15)) (justify left bottom) hide)
    )
    (property "Manufacturer" "" (at 403.86 200.66 0)
      (effects (font (size 1.27 1.27) (thickness 0.15)) (justify left bottom) hide)
    )
    (property "Author" "Antmicro" (at 403.86 198.12 0)
      (effects (font (size 1.27 1.27) (thickness 0.15)) (justify left bottom) hide)
    )
    (property "License" "Apache-2.0" (at 403.86 195.58 0)
      (effects (font (size 1.27 1.27) (thickness 0.15)) (justify left bottom) hide)
    )
    (pin "1")
    (instances
      (project "kria-k26-devboard"
        (path ""
          (reference "TP59") (unit 1)
        )
      )
    )
  )

  (symbol (lib_id "kria-k26-devboard:Spacer_Drill4.45mm_H5mm_9774050960R") (at 120.65 261.62 180) (unit 1)
    (in_bom yes) (on_board yes) (dnp no)
    (property "Reference" "SP2" (at 110.49 260.35 0)
      (effects (font (size 1.27 1.27) (thickness 0.15)))
    )
    (property "Value" "Spacer_Drill4.45mm_H5mm_9774050960R" (at 98.425 266.065 0)
      (effects (font (size 1.27 1.27) (thickness 0.15)))
    )
    (property "Footprint" "kria-k26-devboard-footprints:Spacer_Drill4.45mm_H5mm_9774050960R" (at 97.79 254 0)
      (effects (font (size 1.27 1.27) (thickness 0.15)) (justify left bottom) hide)
    )
    (property "Datasheet" "https://www.we-online.com/components/products/datasheet/9774050960R.pdf" (at 97.79 251.46 0)
      (effects (font (size 1.27 1.27) (thickness 0.15)) (justify left bottom) hide)
    )
    (property "Manufacturer" "Würth Elektronik" (at 97.79 248.92 0)
      (effects (font (size 1.27 1.27) (thickness 0.15)) (justify left bottom) hide)
    )
    (property "MPN" "9774050960R" (at 97.79 246.38 0)
      (effects (font (size 1.27 1.27) (thickness 0.15)) (justify left bottom) hide)
    )
    (property "Author" "Antmicro" (at 97.79 243.84 0)
      (effects (font (size 1.27 1.27) (thickness 0.15)) (justify left bottom) hide)
    )
    (property "License" "Apache-2.0" (at 97.79 241.3 0)
      (effects (font (size 1.27 1.27) (thickness 0.15)) (justify left bottom) hide)
    )
    (pin "1")
    (instances
      (project "kria-k26-devboard"
        (path ""
          (reference "SP2") (unit 1)
        )
      )
    )
  )

  (symbol (lib_id "kria-k26-devboard:Spacer_Drill4.45mm_H5mm_9774050960R") (at 120.65 269.875 180) (unit 1)
    (in_bom yes) (on_board yes) (dnp no)
    (property "Reference" "SP3" (at 110.49 268.605 0)
      (effects (font (size 1.27 1.27) (thickness 0.15)))
    )
    (property "Value" "Spacer_Drill4.45mm_H5mm_9774050960R" (at 98.425 274.32 0)
      (effects (font (size 1.27 1.27) (thickness 0.15)))
    )
    (property "Footprint" "kria-k26-devboard-footprints:Spacer_Drill4.45mm_H5mm_9774050960R" (at 97.79 262.255 0)
      (effects (font (size 1.27 1.27) (thickness 0.15)) (justify left bottom) hide)
    )
    (property "Datasheet" "https://www.we-online.com/components/products/datasheet/9774050960R.pdf" (at 97.79 259.715 0)
      (effects (font (size 1.27 1.27) (thickness 0.15)) (justify left bottom) hide)
    )
    (property "Manufacturer" "Würth Elektronik" (at 97.79 257.175 0)
      (effects (font (size 1.27 1.27) (thickness 0.15)) (justify left bottom) hide)
    )
    (property "MPN" "9774050960R" (at 97.79 254.635 0)
      (effects (font (size 1.27 1.27) (thickness 0.15)) (justify left bottom) hide)
    )
    (property "Author" "Antmicro" (at 97.79 252.095 0)
      (effects (font (size 1.27 1.27) (thickness 0.15)) (justify left bottom) hide)
    )
    (property "License" "Apache-2.0" (at 97.79 249.555 0)
      (effects (font (size 1.27 1.27) (thickness 0.15)) (justify left bottom) hide)
    )
    (pin "1")
    (instances
      (project "kria-k26-devboard"
        (path ""
          (reference "SP3") (unit 1)
        )
      )
    )
  )

  (symbol (lib_id "kria-k26-devboard:GND") (at 314.96 203.2 0) (unit 1)
    (in_bom yes) (on_board yes) (dnp no) (fields_autoplaced)
    (property "Reference" "#PWR0224" (at 314.96 209.55 0)
      (effects (font (size 1.27 1.27)) hide)
    )
    (property "Value" "GND" (at 314.96 208.28 0)
      (effects (font (size 1.27 1.27)))
    )
    (property "Footprint" "" (at 323.85 210.82 0)
      (effects (font (size 1.27 1.27) (thickness 0.15)) (justify left bottom) hide)
    )
    (property "Datasheet" "" (at 323.85 215.9 0)
      (effects (font (size 1.27 1.27) (thickness 0.15)) (justify left bottom) hide)
    )
    (property "Author" "Antmicro" (at 323.85 210.82 0)
      (effects (font (size 1.27 1.27) (thickness 0.15)) (justify left bottom) hide)
    )
    (property "License" "Apache-2.0" (at 323.85 213.36 0)
      (effects (font (size 1.27 1.27) (thickness 0.15)) (justify left bottom) hide)
    )
    (pin "1")
    (instances
      (project "kria-k26-devboard"
        (path ""
          (reference "#PWR0224") (unit 1)
        )
      )
    )
  )

  (symbol (lib_id "kria-k26-devboard:C_100n_0402") (at 127.635 200.66 270) (unit 1)
    (in_bom yes) (on_board yes) (dnp no)
    (property "Reference" "C126" (at 128.27 201.295 90)
      (effects (font (size 1.524 1.524)) (justify left))
    )
    (property "Value" "C_100n_0402" (at 123.825 200.66 0)
      (effects (font (size 1.27 1.27) (thickness 0.15)) (justify left bottom) hide)
    )
    (property "Footprint" "kria-k26-devboard-footprints:C_0402_1005Metric" (at 132.715 205.74 0)
      (effects (font (size 1.27 1.27) (thickness 0.15)) (justify left bottom) hide)
    )
    (property "Datasheet" "https://search.murata.co.jp/Ceramy/image/img/A01X/G101/ENG/GRM155R61H104KE14-01.pdf" (at 127.635 200.66 0)
      (effects (font (size 1.27 1.27) (thickness 0.15)) (justify left bottom) hide)
    )
    (property "Manufacturer" "Murata" (at 137.795 205.74 0)
      (effects (font (size 1.27 1.27) (thickness 0.15)) (justify left bottom) hide)
    )
    (property "MPN" "GRM155R61H104KE14D" (at 135.255 205.74 0)
      (effects (font (size 1.27 1.27) (thickness 0.15)) (justify left bottom) hide)
    )
    (property "Val" "100n" (at 128.27 205.105 90)
      (effects (font (size 1.27 1.27) (thickness 0.15)) (justify left))
    )
    (property "License" "Apache-2.0" (at 104.775 220.98 0)
      (effects (font (size 1.27 1.27) (thickness 0.15)) (justify left bottom) hide)
    )
    (property "Author" "Antmicro" (at 102.235 220.98 0)
      (effects (font (size 1.27 1.27) (thickness 0.15)) (justify left bottom) hide)
    )
    (property "Voltage" "50V" (at 99.695 220.98 0)
      (effects (font (size 1.27 1.27)) (justify left bottom) hide)
    )
    (property "Dielectric" "X5R" (at 97.155 220.98 0)
      (effects (font (size 1.27 1.27)) (justify left bottom) hide)
    )
    (pin "1")
    (pin "2")
    (instances
      (project "kria-k26-devboard"
        (path ""
          (reference "C126") (unit 1)
        )
      )
    )
  )

  (symbol (lib_id "kria-k26-devboard:GND") (at 278.13 228.6 0) (unit 1)
    (in_bom yes) (on_board yes) (dnp no) (fields_autoplaced)
    (property "Reference" "#PWR0220" (at 278.13 234.95 0)
      (effects (font (size 1.27 1.27)) hide)
    )
    (property "Value" "GND" (at 278.13 233.68 0)
      (effects (font (size 1.27 1.27)))
    )
    (property "Footprint" "" (at 287.02 236.22 0)
      (effects (font (size 1.27 1.27) (thickness 0.15)) (justify left bottom) hide)
    )
    (property "Datasheet" "" (at 287.02 241.3 0)
      (effects (font (size 1.27 1.27) (thickness 0.15)) (justify left bottom) hide)
    )
    (property "Author" "Antmicro" (at 287.02 236.22 0)
      (effects (font (size 1.27 1.27) (thickness 0.15)) (justify left bottom) hide)
    )
    (property "License" "Apache-2.0" (at 287.02 238.76 0)
      (effects (font (size 1.27 1.27) (thickness 0.15)) (justify left bottom) hide)
    )
    (pin "1")
    (instances
      (project "kria-k26-devboard"
        (path ""
          (reference "#PWR0220") (unit 1)
        )
      )
    )
  )

  (symbol (lib_id "kria-k26-devboard:GND") (at 314.96 228.6 0) (unit 1)
    (in_bom yes) (on_board yes) (dnp no) (fields_autoplaced)
    (property "Reference" "#PWR0213" (at 314.96 234.95 0)
      (effects (font (size 1.27 1.27)) hide)
    )
    (property "Value" "GND" (at 314.96 233.172 0)
      (effects (font (size 1.27 1.27)))
    )
    (property "Footprint" "" (at 323.85 236.22 0)
      (effects (font (size 1.27 1.27) (thickness 0.15)) (justify left bottom) hide)
    )
    (property "Datasheet" "" (at 323.85 241.3 0)
      (effects (font (size 1.27 1.27) (thickness 0.15)) (justify left bottom) hide)
    )
    (property "Author" "Antmicro" (at 323.85 236.22 0)
      (effects (font (size 1.27 1.27) (thickness 0.15)) (justify left bottom) hide)
    )
    (property "License" "Apache-2.0" (at 323.85 238.76 0)
      (effects (font (size 1.27 1.27) (thickness 0.15)) (justify left bottom) hide)
    )
    (pin "1")
    (instances
      (project "kria-k26-devboard"
        (path ""
          (reference "#PWR0213") (unit 1)
        )
      )
    )
  )

  (symbol (lib_id "kria-k26-devboard:GND") (at 121.92 262.89 0) (unit 1)
    (in_bom yes) (on_board yes) (dnp no) (fields_autoplaced)
    (property "Reference" "#PWR0217" (at 121.92 269.24 0)
      (effects (font (size 1.27 1.27)) hide)
    )
    (property "Value" "GND" (at 124.46 264.1599 0)
      (effects (font (size 1.27 1.27)) (justify left))
    )
    (property "Footprint" "" (at 130.81 270.51 0)
      (effects (font (size 1.27 1.27) (thickness 0.15)) (justify left bottom) hide)
    )
    (property "Datasheet" "" (at 130.81 275.59 0)
      (effects (font (size 1.27 1.27) (thickness 0.15)) (justify left bottom) hide)
    )
    (property "Author" "Antmicro" (at 130.81 270.51 0)
      (effects (font (size 1.27 1.27) (thickness 0.15)) (justify left bottom) hide)
    )
    (property "License" "Apache-2.0" (at 130.81 273.05 0)
      (effects (font (size 1.27 1.27) (thickness 0.15)) (justify left bottom) hide)
    )
    (pin "1")
    (instances
      (project "kria-k26-devboard"
        (path ""
          (reference "#PWR0217") (unit 1)
        )
      )
    )
  )

  (symbol (lib_id "kria-k26-devboard:GND") (at 278.13 203.2 0) (unit 1)
    (in_bom yes) (on_board yes) (dnp no) (fields_autoplaced)
    (property "Reference" "#PWR0227" (at 278.13 209.55 0)
      (effects (font (size 1.27 1.27)) hide)
    )
    (property "Value" "GND" (at 278.13 207.645 0)
      (effects (font (size 1.27 1.27)))
    )
    (property "Footprint" "" (at 287.02 210.82 0)
      (effects (font (size 1.27 1.27) (thickness 0.15)) (justify left bottom) hide)
    )
    (property "Datasheet" "" (at 287.02 215.9 0)
      (effects (font (size 1.27 1.27) (thickness 0.15)) (justify left bottom) hide)
    )
    (property "Author" "Antmicro" (at 287.02 210.82 0)
      (effects (font (size 1.27 1.27) (thickness 0.15)) (justify left bottom) hide)
    )
    (property "License" "Apache-2.0" (at 287.02 213.36 0)
      (effects (font (size 1.27 1.27) (thickness 0.15)) (justify left bottom) hide)
    )
    (pin "1")
    (instances
      (project "kria-k26-devboard"
        (path ""
          (reference "#PWR0227") (unit 1)
        )
      )
    )
  )

  (symbol (lib_id "kria-k26-devboard:TP_0.75mm_SMD") (at 386.08 203.2 0) (mirror x) (unit 1)
    (in_bom yes) (on_board yes) (dnp no)
    (property "Reference" "TP53" (at 393.065 203.2 0)
      (effects (font (size 1.27 1.27)))
    )
    (property "Value" "TP_0.75mm_SMD" (at 386.08 200.66 0)
      (effects (font (size 1.27 1.27) (thickness 0.15)) (justify left bottom) hide)
    )
    (property "Footprint" "kria-k26-devboard-footprints:TP_SMD_0.75mm" (at 391.16 208.28 0)
      (effects (font (size 1.27 1.27) (thickness 0.15)) (justify left bottom) hide)
    )
    (property "Datasheet" "" (at 391.16 210.82 0)
      (effects (font (size 1.27 1.27) (thickness 0.15)) (justify left bottom) hide)
    )
    (property "MPN" "" (at 403.86 187.96 0)
      (effects (font (size 1.27 1.27) (thickness 0.15)) (justify left bottom) hide)
    )
    (property "Manufacturer" "" (at 403.86 185.42 0)
      (effects (font (size 1.27 1.27) (thickness 0.15)) (justify left bottom) hide)
    )
    (property "Author" "Antmicro" (at 403.86 182.88 0)
      (effects (font (size 1.27 1.27) (thickness 0.15)) (justify left bottom) hide)
    )
    (property "License" "Apache-2.0" (at 403.86 180.34 0)
      (effects (font (size 1.27 1.27) (thickness 0.15)) (justify left bottom) hide)
    )
    (pin "1")
    (instances
      (project "kria-k26-devboard"
        (path ""
          (reference "TP53") (unit 1)
        )
      )
    )
  )

  (symbol (lib_id "kria-k26-devboard:Spacer_Drill4.45mm_H5mm_9774050960R") (at 120.65 278.765 180) (unit 1)
    (in_bom yes) (on_board yes) (dnp no)
    (property "Reference" "SP4" (at 110.49 277.495 0)
      (effects (font (size 1.27 1.27) (thickness 0.15)))
    )
    (property "Value" "Spacer_Drill4.45mm_H5mm_9774050960R" (at 98.425 283.21 0)
      (effects (font (size 1.27 1.27) (thickness 0.15)))
    )
    (property "Footprint" "kria-k26-devboard-footprints:Spacer_Drill4.45mm_H5mm_9774050960R" (at 97.79 271.145 0)
      (effects (font (size 1.27 1.27) (thickness 0.15)) (justify left bottom) hide)
    )
    (property "Datasheet" "https://www.we-online.com/components/products/datasheet/9774050960R.pdf" (at 97.79 268.605 0)
      (effects (font (size 1.27 1.27) (thickness 0.15)) (justify left bottom) hide)
    )
    (property "Manufacturer" "Würth Elektronik" (at 97.79 266.065 0)
      (effects (font (size 1.27 1.27) (thickness 0.15)) (justify left bottom) hide)
    )
    (property "MPN" "9774050960R" (at 97.79 263.525 0)
      (effects (font (size 1.27 1.27) (thickness 0.15)) (justify left bottom) hide)
    )
    (property "Author" "Antmicro" (at 97.79 260.985 0)
      (effects (font (size 1.27 1.27) (thickness 0.15)) (justify left bottom) hide)
    )
    (property "License" "Apache-2.0" (at 97.79 258.445 0)
      (effects (font (size 1.27 1.27) (thickness 0.15)) (justify left bottom) hide)
    )
    (pin "1")
    (instances
      (project "kria-k26-devboard"
        (path ""
          (reference "SP4") (unit 1)
        )
      )
    )
  )

  (symbol (lib_id "kria-k26-devboard:R_0R_0402") (at 19.685 31.75 90) (unit 1)
    (in_bom yes) (on_board yes) (dnp no) (fields_autoplaced)
    (property "Reference" "R170" (at 17.78 27.94 90)
      (effects (font (size 1.524 1.524)) (justify left))
    )
    (property "Value" "R_0R_0402" (at 23.495 31.75 0)
      (effects (font (size 1.27 1.27) (thickness 0.15)) (justify left bottom) hide)
    )
    (property "Footprint" "kria-k26-devboard-footprints:R_0402_1005Metric" (at 14.605 26.67 0)
      (effects (font (size 1.27 1.27) (thickness 0.15)) (justify left bottom) hide)
    )
    (property "Datasheet" "https://industrial.panasonic.com/cdbs/www-data/pdf/RDA0000/AOA0000C301.pdf" (at 19.685 31.75 0)
      (effects (font (size 1.27 1.27) (thickness 0.15)) (justify left bottom) hide)
    )
    (property "Manufacturer" "Panasonic" (at 9.525 26.67 0)
      (effects (font (size 1.27 1.27) (thickness 0.15)) (justify left bottom) hide)
    )
    (property "MPN" "ERJ2GE0R00X" (at 12.065 26.67 0)
      (effects (font (size 1.27 1.27) (thickness 0.15)) (justify left bottom) hide)
    )
    (property "Val" "0R" (at 17.78 31.1149 90)
      (effects (font (size 1.27 1.27) (thickness 0.15)) (justify left))
    )
    (property "License" "Apache-2.0" (at 45.085 11.43 0)
      (effects (font (size 1.27 1.27) (thickness 0.15)) (justify left bottom) hide)
    )
    (property "Author" "Antmicro" (at 47.625 11.43 0)
      (effects (font (size 1.27 1.27) (thickness 0.15)) (justify left bottom) hide)
    )
    (property "Tolerance" "~" (at 29.845 11.43 0)
      (effects (font (size 1.27 1.27)) (justify left bottom) hide)
    )
    (property "Current" "1A" (at 50.165 11.43 0)
      (effects (font (size 1.27 1.27) (thickness 0.15)) (justify left bottom) hide)
    )
    (pin "1")
    (pin "2")
    (instances
      (project "kria-k26-devboard"
        (path ""
          (reference "R170") (unit 1)
        )
      )
    )
  )

  (symbol (lib_id "kria-k26-devboard:C_100n_0402") (at 134.62 200.66 270) (unit 1)
    (in_bom yes) (on_board yes) (dnp no)
    (property "Reference" "C250" (at 134.62 201.295 90)
      (effects (font (size 1.524 1.524)) (justify left))
    )
    (property "Value" "C_100n_0402" (at 130.81 200.66 0)
      (effects (font (size 1.27 1.27) (thickness 0.15)) (justify left bottom) hide)
    )
    (property "Footprint" "kria-k26-devboard-footprints:C_0402_1005Metric" (at 139.7 205.74 0)
      (effects (font (size 1.27 1.27) (thickness 0.15)) (justify left bottom) hide)
    )
    (property "Datasheet" "https://search.murata.co.jp/Ceramy/image/img/A01X/G101/ENG/GRM155R61H104KE14-01.pdf" (at 134.62 200.66 0)
      (effects (font (size 1.27 1.27) (thickness 0.15)) (justify left bottom) hide)
    )
    (property "Manufacturer" "Murata" (at 144.78 205.74 0)
      (effects (font (size 1.27 1.27) (thickness 0.15)) (justify left bottom) hide)
    )
    (property "MPN" "GRM155R61H104KE14D" (at 142.24 205.74 0)
      (effects (font (size 1.27 1.27) (thickness 0.15)) (justify left bottom) hide)
    )
    (property "Val" "100n" (at 134.62 205.105 90)
      (effects (font (size 1.27 1.27) (thickness 0.15)) (justify left))
    )
    (property "License" "Apache-2.0" (at 111.76 220.98 0)
      (effects (font (size 1.27 1.27) (thickness 0.15)) (justify left bottom) hide)
    )
    (property "Author" "Antmicro" (at 109.22 220.98 0)
      (effects (font (size 1.27 1.27) (thickness 0.15)) (justify left bottom) hide)
    )
    (property "Voltage" "50V" (at 106.68 220.98 0)
      (effects (font (size 1.27 1.27)) (justify left bottom) hide)
    )
    (property "Dielectric" "X5R" (at 104.14 220.98 0)
      (effects (font (size 1.27 1.27)) (justify left bottom) hide)
    )
    (pin "1")
    (pin "2")
    (instances
      (project "kria-k26-devboard"
        (path ""
          (reference "C250") (unit 1)
        )
      )
    )
  )

  (symbol (lib_id "kria-k26-devboard:GND") (at 96.52 235.585 0) (unit 1)
    (in_bom yes) (on_board yes) (dnp no) (fields_autoplaced)
    (property "Reference" "#PWR0218" (at 96.52 241.935 0)
      (effects (font (size 1.27 1.27)) hide)
    )
    (property "Value" "GND" (at 96.52 240.665 0)
      (effects (font (size 1.27 1.27)))
    )
    (property "Footprint" "" (at 105.41 243.205 0)
      (effects (font (size 1.27 1.27) (thickness 0.15)) (justify left bottom) hide)
    )
    (property "Datasheet" "" (at 105.41 248.285 0)
      (effects (font (size 1.27 1.27) (thickness 0.15)) (justify left bottom) hide)
    )
    (property "Author" "Antmicro" (at 105.41 243.205 0)
      (effects (font (size 1.27 1.27) (thickness 0.15)) (justify left bottom) hide)
    )
    (property "License" "Apache-2.0" (at 105.41 245.745 0)
      (effects (font (size 1.27 1.27) (thickness 0.15)) (justify left bottom) hide)
    )
    (pin "1")
    (instances
      (project "kria-k26-devboard"
        (path ""
          (reference "#PWR0218") (unit 1)
        )
      )
    )
  )

  (symbol (lib_id "kria-k26-devboard:TP_0.75mm_SMD") (at 386.08 208.28 0) (mirror x) (unit 1)
    (in_bom yes) (on_board yes) (dnp no)
    (property "Reference" "TP55" (at 393.065 208.28 0)
      (effects (font (size 1.27 1.27)))
    )
    (property "Value" "TP_0.75mm_SMD" (at 386.08 205.74 0)
      (effects (font (size 1.27 1.27) (thickness 0.15)) (justify left bottom) hide)
    )
    (property "Footprint" "kria-k26-devboard-footprints:TP_SMD_0.75mm" (at 391.16 213.36 0)
      (effects (font (size 1.27 1.27) (thickness 0.15)) (justify left bottom) hide)
    )
    (property "Datasheet" "" (at 391.16 215.9 0)
      (effects (font (size 1.27 1.27) (thickness 0.15)) (justify left bottom) hide)
    )
    (property "MPN" "" (at 403.86 193.04 0)
      (effects (font (size 1.27 1.27) (thickness 0.15)) (justify left bottom) hide)
    )
    (property "Manufacturer" "" (at 403.86 190.5 0)
      (effects (font (size 1.27 1.27) (thickness 0.15)) (justify left bottom) hide)
    )
    (property "Author" "Antmicro" (at 403.86 187.96 0)
      (effects (font (size 1.27 1.27) (thickness 0.15)) (justify left bottom) hide)
    )
    (property "License" "Apache-2.0" (at 403.86 185.42 0)
      (effects (font (size 1.27 1.27) (thickness 0.15)) (justify left bottom) hide)
    )
    (pin "1")
    (instances
      (project "kria-k26-devboard"
        (path ""
          (reference "TP55") (unit 1)
        )
      )
    )
  )
)
